G04 ================== begin FILE IDENTIFICATION RECORD ==================*
G04 Layout Name:  D:/<user>/Wistron_project/16347-1_ECN/16347-1.brd*
G04 Film Name:    TSILK*
G04 File Format:  Gerber RS274X*
G04 File Origin:  Cadence Allegro 16.5-S056*
G04 Origin Date:  Mon Jun 12 14:22:31 2017*
G04 *
G04 Layer:  VIA CLASS/FILMMASKTOP*
G04 Layer:  REF DES/ASSEMBLY_TOP*
G04 Layer:  PACKAGE GEOMETRY/SILKSCREEN_TOP*
G04 Layer:  DRAWING FORMAT/LAYER_PCB_STORY*
G04 Layer:  DRAWING FORMAT/LAYER_SILK_T*
G04 Layer:  BOARD GEOMETRY/SILKSCREEN_TOP*
G04 *
G04 Offset:    (0.00 0.00)*
G04 Mirror:    No*
G04 Mode:      Positive*
G04 Rotation:  0*
G04 FullContactRelief:  No*
G04 UndefLineWidth:     6.00*
G04 ================== end FILE IDENTIFICATION RECORD ====================*
%FSLAX35Y35*MOIN*%
%IR0*IPPOS*OFA0.00000B0.00000*MIA0B0*SFA1.00000B1.00000*%
%ADD10C,.02*%
%ADD11C,.015*%
%ADD12C,.018*%
%ADD13C,.002*%
%ADD14C,.006*%
G75*
%LPD*%
G75*
G36*
G01X86641Y22096D02*
X86701Y22035D01*
X86762Y21245D01*
X86823Y21184D01*
X86884Y20454D01*
X86944Y20393D01*
X87006Y19663D01*
X87066Y19603D01*
X87127Y18873D01*
X87188Y18812D01*
X87249Y18082D01*
X87309Y18021D01*
X87370Y17292D01*
X87431Y17231D01*
X87492Y16440D01*
X87553Y16379D01*
X87614Y15650D01*
X87674Y15589D01*
X87735Y14859D01*
X87796Y14798D01*
X87857Y14068D01*
X87918Y14007D01*
X87978Y13278D01*
X88039Y13217D01*
X88100Y12487D01*
X88161Y12426D01*
X88222Y11635D01*
X88283Y11574D01*
X88343Y10845D01*
X88404Y10784D01*
X88465Y10054D01*
X88526Y9993D01*
Y9689D01*
X93026D01*
X93148Y9932D01*
X93331Y10176D01*
X93452Y10480D01*
X93635Y10723D01*
X93756Y11027D01*
X93939Y11270D01*
X94061Y11574D01*
X94243Y11818D01*
X94365Y12122D01*
X94547Y12365D01*
X94669Y12669D01*
X94851Y12913D01*
X94912Y13095D01*
X95094Y13338D01*
X95216Y13643D01*
X95398Y13886D01*
X95520Y14190D01*
X95703Y14433D01*
X95824Y14737D01*
X96007Y14980D01*
X96128Y15285D01*
X96311Y15528D01*
X96432Y15832D01*
X96615Y16075D01*
X96676Y16257D01*
X96858Y16501D01*
X96980Y16805D01*
X97162Y17048D01*
X97345Y17413D01*
X97406Y17352D01*
X97466Y16866D01*
X97527Y16136D01*
X97588Y15771D01*
X97649Y14920D01*
X97709Y14859D01*
X97770Y13764D01*
X97831Y13703D01*
X97892Y12609D01*
X97953Y12548D01*
X98014Y11392D01*
X98074Y11331D01*
X98135Y10237D01*
X98196Y10176D01*
Y9689D01*
X102636D01*
X102757Y9932D01*
X102940Y10176D01*
X103001Y10358D01*
X103183Y10602D01*
X103244Y10784D01*
X103427Y11027D01*
X103487Y11209D01*
X103670Y11453D01*
X103731Y11635D01*
X103913Y11879D01*
X103974Y12061D01*
X104156Y12304D01*
X104217Y12487D01*
X104400Y12730D01*
X104461Y12913D01*
X104643Y13156D01*
X104704Y13338D01*
X104886Y13581D01*
X105008Y13886D01*
X105191Y14129D01*
X105251Y14311D01*
X105433Y14555D01*
X105494Y14737D01*
X105677Y14980D01*
X105738Y15163D01*
X105920Y15406D01*
X105981Y15589D01*
X106163Y15832D01*
X106224Y16014D01*
X106407Y16257D01*
X106468Y16440D01*
X106650Y16683D01*
X106711Y16866D01*
X106893Y17109D01*
X106954Y17292D01*
X107137Y17535D01*
X107197Y17717D01*
X107380Y17961D01*
X107502Y18265D01*
X107684Y18508D01*
X107745Y18691D01*
X107927Y18934D01*
X107988Y19116D01*
X108170Y19359D01*
X108231Y19542D01*
X108414Y19785D01*
X108474Y19968D01*
X108657Y20211D01*
X108718Y20393D01*
X108900Y20637D01*
X108961Y20819D01*
X109144Y21062D01*
X109204Y21245D01*
X109387Y21488D01*
X109448Y21670D01*
X109630Y21914D01*
X109752Y22218D01*
X109934Y22461D01*
X109995Y22583D01*
Y22644D01*
X104947D01*
X104704Y22157D01*
X104643Y21914D01*
X104461Y21610D01*
X104400Y21367D01*
X104278Y21184D01*
X104217Y20941D01*
X104035Y20637D01*
X103974Y20393D01*
X103791Y20089D01*
X103731Y19846D01*
X103609Y19663D01*
X103548Y19420D01*
X103366Y19116D01*
X103305Y18873D01*
X103122Y18569D01*
X103062Y18326D01*
X102940Y18143D01*
X102879Y17900D01*
X102697Y17596D01*
X102636Y17352D01*
X102454Y17048D01*
X102393Y16805D01*
X102271Y16622D01*
X102210Y16379D01*
X102028Y16075D01*
X101967Y15832D01*
X101785Y15528D01*
X101724Y15285D01*
X101602Y15102D01*
X101541Y14859D01*
X101359Y14555D01*
X101298Y14615D01*
X101237Y15589D01*
X101176Y15954D01*
X101115Y16927D01*
X101055Y17292D01*
X100994Y18265D01*
X100933Y18630D01*
X100872Y19603D01*
X100811Y19968D01*
X100750Y20941D01*
X100690Y21306D01*
X100629Y22279D01*
X100568Y22644D01*
X96067D01*
Y22583D01*
X95885Y22339D01*
X95703Y21914D01*
X95520Y21670D01*
X95338Y21245D01*
X95155Y21002D01*
X94973Y20576D01*
X94790Y20333D01*
X94669Y20028D01*
X94486Y19785D01*
X94304Y19359D01*
X94121Y19116D01*
X93939Y18691D01*
X93756Y18447D01*
X93574Y18021D01*
X93391Y17778D01*
X93270Y17474D01*
X93087Y17231D01*
X92905Y16805D01*
X92722Y16562D01*
X92540Y16136D01*
X92357Y15893D01*
X92175Y15467D01*
X91993Y15224D01*
X91871Y14920D01*
X91689Y14676D01*
X91567Y14433D01*
X91506Y14494D01*
X91445Y15832D01*
X91384Y16562D01*
X91324Y17900D01*
X91263Y18630D01*
X91202Y19968D01*
X91141Y20819D01*
X91080Y22035D01*
X91020Y22644D01*
X86580D01*
X86641Y22096D01*
G37*
G36*
G01X80194Y22279D02*
X80133Y22218D01*
X80072Y21731D01*
X80011Y21670D01*
X79950Y21184D01*
X79890Y21123D01*
X79829Y20576D01*
X79768Y20515D01*
X79707Y20028D01*
X79646Y19968D01*
X79585Y19481D01*
X79525Y19420D01*
X79464Y18873D01*
X79403Y18812D01*
X79342Y18326D01*
X79281Y18265D01*
X79220Y17778D01*
X79160Y17717D01*
X79099Y17170D01*
X79038Y17109D01*
X78977Y16622D01*
X78917Y16562D01*
X78856Y16075D01*
X78795Y16014D01*
X78734Y15467D01*
X78673Y15406D01*
X78612Y14920D01*
X78552Y14859D01*
X78491Y14372D01*
X78430Y14311D01*
X78369Y13764D01*
X78308Y13703D01*
X78248Y13217D01*
X78187Y13156D01*
X78126Y12669D01*
X78065Y12609D01*
X78004Y12061D01*
X77943Y12000D01*
X77883Y11514D01*
X77822Y11453D01*
X77761Y10967D01*
X77700Y10906D01*
X77639Y10358D01*
X77578Y10297D01*
X77518Y9811D01*
X77457Y9750D01*
Y9689D01*
X82809D01*
X82870Y10054D01*
X82931Y10115D01*
X82991Y10602D01*
X83052Y10662D01*
X83113Y11209D01*
X83174Y11270D01*
X83235Y11757D01*
X83295Y11818D01*
X83356Y12304D01*
X83417Y12365D01*
X83478Y12913D01*
X83539Y12973D01*
X83600Y13460D01*
X83660Y13521D01*
X83721Y14007D01*
X83782Y14068D01*
X83843Y14615D01*
X83904Y14676D01*
X83965Y15163D01*
X84025Y15224D01*
X84086Y15710D01*
X84147Y15771D01*
X84208Y16319D01*
X84269Y16379D01*
X84330Y16866D01*
X84390Y16927D01*
X84451Y17413D01*
X84512Y17474D01*
X84573Y17961D01*
X84633Y18021D01*
X84694Y18569D01*
X84755Y18630D01*
X84816Y19116D01*
X84877Y19177D01*
X84937Y19663D01*
X84998Y19724D01*
X85059Y20272D01*
X85120Y20333D01*
X85181Y20819D01*
X85242Y20880D01*
X85302Y21367D01*
X85363Y21427D01*
X85424Y21975D01*
X85485Y22035D01*
X85546Y22522D01*
X85607Y22583D01*
Y22644D01*
X80254D01*
X80194Y22279D01*
G37*
G36*
G01X55927Y21914D02*
X55988Y21427D01*
X56048Y21367D01*
X56109Y20637D01*
X56170Y20576D01*
X56231Y19785D01*
X56292Y19724D01*
X56353Y18994D01*
X56413Y18934D01*
X56474Y18204D01*
X56535Y18143D01*
X56596Y17413D01*
X56657Y17352D01*
X56717Y16622D01*
X56778Y16562D01*
X56839Y15771D01*
X56900Y15710D01*
X56961Y14980D01*
X57022Y14920D01*
X57082Y14190D01*
X57143Y14129D01*
X57204Y13399D01*
X57265Y13338D01*
X57326Y12609D01*
X57387Y12548D01*
X57447Y11818D01*
X57508Y11757D01*
X57569Y10967D01*
X57630Y10906D01*
X57691Y10176D01*
X57752Y10115D01*
X57812Y9689D01*
X62252D01*
X62435Y9932D01*
X62556Y10237D01*
X62739Y10480D01*
X62860Y10784D01*
X63043Y11027D01*
X63104Y11209D01*
X63286Y11453D01*
X63407Y11757D01*
X63590Y12000D01*
X63712Y12304D01*
X63894Y12548D01*
X64016Y12852D01*
X64198Y13095D01*
X64259Y13278D01*
X64441Y13521D01*
X64563Y13825D01*
X64746Y14068D01*
X64867Y14372D01*
X65050Y14615D01*
X65171Y14920D01*
X65354Y15163D01*
X65476Y15467D01*
X65658Y15710D01*
X65719Y15893D01*
X65901Y16136D01*
X66023Y16440D01*
X66205Y16683D01*
X66327Y16987D01*
X66509Y17231D01*
Y17292D01*
X66631Y17413D01*
X66692Y17352D01*
X66753Y16257D01*
X66813Y16197D01*
X66874Y15102D01*
X66935Y15041D01*
X66996Y13946D01*
X67057Y13886D01*
X67118Y12730D01*
X67178Y12669D01*
X67239Y11574D01*
X67300Y11514D01*
X67361Y10419D01*
X67422Y10358D01*
X67482Y9689D01*
X71922D01*
X72044Y9993D01*
X72226Y10237D01*
X72287Y10419D01*
X72470Y10662D01*
X72530Y10845D01*
X72713Y11088D01*
X72774Y11270D01*
X72956Y11514D01*
X73078Y11818D01*
X73260Y12061D01*
X73321Y12244D01*
X73504Y12487D01*
X73565Y12669D01*
X73747Y12913D01*
X73807Y13095D01*
X73990Y13338D01*
X74051Y13521D01*
X74233Y13764D01*
X74294Y13946D01*
X74477Y14190D01*
X74537Y14372D01*
X74720Y14615D01*
X74781Y14798D01*
X74963Y15041D01*
X75024Y15224D01*
X75207Y15467D01*
X75328Y15771D01*
X75511Y16014D01*
X75571Y16197D01*
X75754Y16440D01*
X75815Y16622D01*
X75997Y16866D01*
X76058Y17048D01*
X76241Y17292D01*
X76301Y17474D01*
X76484Y17717D01*
X76544Y17900D01*
X76727Y18143D01*
X76788Y18326D01*
X76970Y18569D01*
X77031Y18751D01*
X77213Y18994D01*
X77274Y19177D01*
X77457Y19420D01*
X77578Y19724D01*
X77761Y19968D01*
X77822Y20150D01*
X78004Y20393D01*
X78065Y20576D01*
X78248Y20819D01*
X78308Y21002D01*
X78491Y21245D01*
X78552Y21427D01*
X78734Y21670D01*
X78795Y21853D01*
X78977Y22096D01*
X79038Y22279D01*
X79220Y22522D01*
Y22583D01*
X79281Y22644D01*
X74172D01*
X74112Y22400D01*
X73869Y21975D01*
X73807Y21731D01*
X73625Y21427D01*
X73565Y21184D01*
X73443Y21002D01*
X73382Y20758D01*
X73200Y20454D01*
X73139Y20211D01*
X72956Y19907D01*
X72895Y19663D01*
X72774Y19481D01*
X72713Y19238D01*
X72530Y18934D01*
X72470Y18691D01*
X72287Y18386D01*
X72226Y18143D01*
X72105Y17961D01*
X72044Y17717D01*
X71861Y17413D01*
X71801Y17170D01*
X71618Y16866D01*
X71557Y16622D01*
X71436Y16440D01*
X71375Y16197D01*
X71193Y15893D01*
X71131Y15650D01*
X70949Y15345D01*
X70888Y15102D01*
X70767Y14920D01*
X70706Y14676D01*
X70584Y14555D01*
X70524Y14615D01*
X70463Y15832D01*
X70402Y15893D01*
X70341Y17170D01*
X70280Y17231D01*
X70219Y18508D01*
X70159Y18569D01*
X70098Y19907D01*
X70037Y19968D01*
X69976Y21245D01*
X69915Y21306D01*
X69854Y22583D01*
X69794Y22644D01*
X65293D01*
X65111Y22218D01*
X64928Y21975D01*
X64746Y21549D01*
X64563Y21306D01*
X64381Y20880D01*
X64198Y20637D01*
X64016Y20211D01*
X63833Y19968D01*
X63712Y19663D01*
X63529Y19420D01*
X63347Y18994D01*
X63164Y18751D01*
X62982Y18326D01*
X62799Y18082D01*
X62678Y17778D01*
X62495Y17535D01*
X62313Y17109D01*
X62130Y16866D01*
X61948Y16440D01*
X61765Y16197D01*
X61583Y15771D01*
X61400Y15528D01*
X61279Y15224D01*
X61096Y14980D01*
X60914Y14555D01*
X60793Y14433D01*
X60731Y14494D01*
X60671Y16440D01*
X60610Y16501D01*
X60549Y18508D01*
X60488Y18569D01*
X60428Y20576D01*
X60367Y20637D01*
X60306Y22644D01*
X55805D01*
X55927Y21914D01*
G37*
G36*
G01X83721Y29091D02*
X83235Y29030D01*
X83052Y28908D01*
X82809Y28847D01*
X82566Y28726D01*
X82261Y28482D01*
X82201D01*
X81532Y27752D01*
Y27692D01*
X81349Y27448D01*
X81228Y27205D01*
X81167Y26901D01*
X81106Y26840D01*
X81045Y26232D01*
X81106Y25441D01*
X81167Y25380D01*
X81228Y25137D01*
X81410Y24894D01*
Y24833D01*
X81957Y24346D01*
X82018D01*
X82140Y24225D01*
X82383Y24164D01*
X82444Y24103D01*
X82931Y24043D01*
X82991Y23981D01*
X83965Y24043D01*
X84025Y24103D01*
X84330Y24164D01*
X84390Y24225D01*
X84633Y24286D01*
X84877Y24407D01*
X85242Y24711D01*
X85302D01*
X85972Y25441D01*
X86032Y25624D01*
X86215Y25867D01*
X86276Y26110D01*
X86337Y26171D01*
X86397Y26658D01*
X86458Y26719D01*
X86397Y27631D01*
X86337Y27692D01*
X86276Y27935D01*
X86154Y28178D01*
X85728Y28665D01*
X85485Y28847D01*
X85120Y29030D01*
X84694Y29091D01*
X84633Y29151D01*
X83782D01*
X83721Y29091D01*
G37*
G36*
G01X135539Y22887D02*
X134809Y22826D01*
X134748Y22765D01*
X134383Y22704D01*
X134323Y22644D01*
X134019Y22583D01*
X133958Y22522D01*
X133715Y22461D01*
X133654Y22400D01*
X133411Y22339D01*
X133167Y22218D01*
X132924Y22035D01*
X132863D01*
X132559Y21792D01*
X132498D01*
X132012Y21367D01*
X131951D01*
X131282Y20697D01*
X131221Y20758D01*
X131282Y21245D01*
X131343Y21306D01*
X131404Y21792D01*
X131464Y21853D01*
X131525Y22339D01*
X131586Y22400D01*
Y22644D01*
X126964D01*
X126903Y22218D01*
X126842Y22157D01*
X126781Y21610D01*
X126720Y21549D01*
X126659Y21062D01*
X126599Y21002D01*
X126538Y20515D01*
X126477Y20454D01*
X126416Y19907D01*
X126356Y19846D01*
X126294Y19359D01*
X126234Y19298D01*
X126173Y18812D01*
X126112Y18751D01*
X126051Y18265D01*
X125991Y18204D01*
X125930Y17656D01*
X125869Y17596D01*
X125808Y17109D01*
X125747Y17048D01*
X125687Y16562D01*
X125626Y16501D01*
X125565Y15954D01*
X125504Y15893D01*
X125443Y15406D01*
X125382Y15345D01*
X125322Y14859D01*
X125261Y14798D01*
X125200Y14250D01*
X125139Y14190D01*
X125078Y13703D01*
X125017Y13643D01*
X124957Y13156D01*
X124896Y13095D01*
X124835Y12609D01*
X124774Y12548D01*
X124713Y12000D01*
X124652Y11939D01*
X124592Y11453D01*
X124531Y11392D01*
X124470Y10906D01*
X124409Y10845D01*
X124348Y10297D01*
X124287Y10237D01*
X124227Y9750D01*
X124166Y9689D01*
X129214D01*
X129275Y10237D01*
X129335Y10297D01*
X129396Y10784D01*
X129457Y10845D01*
X129518Y11331D01*
X129579Y11392D01*
X129640Y11879D01*
X129700Y11939D01*
X129761Y12426D01*
X129822Y12487D01*
X129883Y13034D01*
X129944Y13095D01*
X130005Y13581D01*
X130065Y13643D01*
X130126Y14129D01*
X130187Y14190D01*
X130248Y14676D01*
X130309Y14737D01*
X130370Y15224D01*
X130430Y15285D01*
X130491Y15771D01*
X130552Y15832D01*
X130613Y16197D01*
X130674Y16257D01*
X130734Y16562D01*
X130795Y16622D01*
X130856Y16927D01*
X131282Y17778D01*
X131525Y18082D01*
Y18143D01*
X132072Y18751D01*
X132376Y18994D01*
X132863Y19238D01*
X133350Y19298D01*
X133411Y19359D01*
X134019Y19298D01*
X134383Y18994D01*
X134505Y18812D01*
X134566Y18326D01*
X134505Y17535D01*
X134444Y17474D01*
X134383Y16927D01*
X134323Y16866D01*
X134262Y16319D01*
X134201Y16257D01*
X134140Y15710D01*
X134080Y15650D01*
X134019Y15163D01*
X133958Y15102D01*
X133897Y14555D01*
X133836Y14494D01*
X133775Y14007D01*
X133715Y13946D01*
X133654Y13460D01*
X133593Y13399D01*
X133532Y12852D01*
X133471Y12791D01*
X133411Y12304D01*
X133350Y12244D01*
X133289Y11696D01*
X133228Y11635D01*
X133167Y11149D01*
X133106Y11088D01*
X133046Y10602D01*
X132985Y10541D01*
X132924Y9993D01*
X132863Y9932D01*
Y9689D01*
X137789D01*
X137850Y9993D01*
X137911Y10054D01*
X137972Y10602D01*
X138033Y10662D01*
X138094Y11149D01*
X138154Y11209D01*
X138215Y11757D01*
X138276Y11818D01*
X138337Y12304D01*
X138398Y12365D01*
X138458Y12852D01*
X138519Y12913D01*
X138580Y13460D01*
X138641Y13521D01*
X138702Y14007D01*
X138763Y14068D01*
X138823Y14615D01*
X138884Y14676D01*
X138945Y15163D01*
X139006Y15224D01*
X139067Y15710D01*
X139128Y15771D01*
X139188Y16319D01*
X139249Y16379D01*
X139310Y16866D01*
X139371Y16927D01*
X139431Y17474D01*
X139493Y17535D01*
X139553Y18143D01*
X139614Y18204D01*
X139675Y18873D01*
X139736Y18934D01*
X139796Y19907D01*
X139736Y20637D01*
X139675Y20697D01*
X139614Y21002D01*
X139553Y21062D01*
X139493Y21306D01*
X139310Y21549D01*
Y21610D01*
X138884Y22096D01*
X138458Y22461D01*
X138094Y22644D01*
X137850Y22704D01*
X137789Y22765D01*
X137364Y22826D01*
X137303Y22887D01*
X136330Y22948D01*
X135600D01*
X135539Y22887D01*
G37*
G36*
G01X120821Y22400D02*
X120639Y22157D01*
X120578Y21975D01*
X120395Y21731D01*
X120334Y21549D01*
X120152Y21306D01*
X120091Y21123D01*
X119909Y20880D01*
X119787Y20576D01*
X119604Y20333D01*
X119544Y20150D01*
X119361Y19907D01*
X119300Y19724D01*
X119118Y19481D01*
X119057Y19298D01*
X118875Y19055D01*
X118753Y18751D01*
X118570Y18508D01*
X118510Y18326D01*
X118327Y18082D01*
X118267Y17900D01*
X118084Y17656D01*
X118023Y17474D01*
X117841Y17231D01*
X117780Y17048D01*
X117598Y16805D01*
X117476Y16501D01*
X117293Y16257D01*
X117233Y16075D01*
X117050Y15832D01*
X116989Y15650D01*
X116807Y15406D01*
Y15345D01*
X116685Y15224D01*
X116624Y15285D01*
X116563Y16257D01*
X116503Y16319D01*
X116442Y17474D01*
X116381Y17535D01*
X116320Y18751D01*
X116259Y18812D01*
X116199Y19968D01*
X116138Y20028D01*
X116077Y21245D01*
X116016Y21306D01*
X115956Y22461D01*
X115894Y22522D01*
Y22644D01*
X111029D01*
X111090Y22583D01*
X111151Y21975D01*
X111211Y21914D01*
X111272Y21306D01*
X111333Y21245D01*
X111394Y20697D01*
X111455Y20637D01*
X111516Y20028D01*
X111576Y19968D01*
X111637Y19359D01*
X111698Y19298D01*
X111759Y18751D01*
X111820Y18691D01*
X111880Y18082D01*
X111941Y18021D01*
X112002Y17413D01*
X112063Y17352D01*
X112124Y16805D01*
X112185Y16744D01*
X112245Y16136D01*
X112306Y16075D01*
X112367Y15467D01*
X112428Y15406D01*
X112489Y14859D01*
X112550Y14798D01*
X112610Y14190D01*
X112671Y14129D01*
X112732Y13521D01*
X112793Y13460D01*
X112854Y12913D01*
X112915Y12852D01*
X112975Y12244D01*
X113036Y12183D01*
X113097Y11574D01*
X113157Y11514D01*
X113219Y10967D01*
X113279Y10906D01*
X113340Y10297D01*
X113401Y10237D01*
X113462Y9628D01*
X113522Y9567D01*
X113401Y9324D01*
X113219Y9081D01*
X113097Y8777D01*
X112915Y8533D01*
X112854Y8351D01*
X112671Y8108D01*
X112610Y7926D01*
X112428Y7682D01*
X112367Y7500D01*
X112185Y7256D01*
X112063Y6952D01*
X111880Y6709D01*
X111820Y6526D01*
X111637Y6283D01*
X111576Y6101D01*
X111394Y5857D01*
X111333Y5675D01*
X111151Y5432D01*
X111029Y5128D01*
X110846Y4884D01*
X110786Y4702D01*
X110603Y4459D01*
X110543Y4276D01*
X110360Y4033D01*
X110299Y3850D01*
X110117Y3607D01*
X109995Y3303D01*
X109874Y3181D01*
X114982D01*
X115043Y3364D01*
X115226Y3607D01*
X115286Y3790D01*
X115469Y4033D01*
X115530Y4215D01*
X115712Y4459D01*
X115834Y4763D01*
X116016Y5006D01*
X116077Y5189D01*
X116259Y5432D01*
X116320Y5614D01*
X116503Y5857D01*
X116563Y6040D01*
X116746Y6283D01*
X116868Y6587D01*
X117050Y6831D01*
X117111Y7013D01*
X117293Y7256D01*
X117354Y7439D01*
X117537Y7682D01*
X117598Y7865D01*
X117780Y8108D01*
X117841Y8290D01*
X118023Y8533D01*
X118145Y8838D01*
X118327Y9081D01*
X118388Y9263D01*
X118570Y9507D01*
X118631Y9689D01*
X118814Y9932D01*
X118875Y10115D01*
X119057Y10358D01*
X119179Y10662D01*
X119361Y10906D01*
X119422Y11088D01*
X119604Y11331D01*
X119665Y11514D01*
X119848Y11757D01*
X119909Y11939D01*
X120091Y12183D01*
X120213Y12487D01*
X120395Y12730D01*
X120456Y12913D01*
X120639Y13156D01*
X120699Y13338D01*
X120882Y13581D01*
X120943Y13764D01*
X121125Y14007D01*
X121186Y14190D01*
X121368Y14433D01*
X121490Y14737D01*
X121672Y14980D01*
X121733Y15163D01*
X121916Y15406D01*
X121976Y15589D01*
X122159Y15832D01*
X122220Y16014D01*
X122402Y16257D01*
X122524Y16562D01*
X122706Y16805D01*
X122767Y16987D01*
X122950Y17231D01*
X123010Y17413D01*
X123193Y17656D01*
X123254Y17839D01*
X123436Y18082D01*
X123558Y18386D01*
X123740Y18630D01*
X123801Y18812D01*
X123983Y19055D01*
X124044Y19238D01*
X124227Y19481D01*
X124287Y19663D01*
X124470Y19907D01*
X124592Y20211D01*
X124774Y20454D01*
X124835Y20637D01*
X125017Y20880D01*
X125078Y21062D01*
X125261Y21306D01*
X125322Y21488D01*
X125504Y21731D01*
X125565Y21914D01*
X125747Y22157D01*
X125869Y22461D01*
X125991Y22583D01*
Y22704D01*
X120943D01*
X120821Y22400D01*
G37*
G36*
G01X158772Y24407D02*
X158468Y24164D01*
X158225Y24103D01*
X158042Y23981D01*
X157008Y23921D01*
X156948Y23981D01*
X156583Y24043D01*
X156218Y24225D01*
X155974Y24407D01*
X155549Y24894D01*
X155306Y25380D01*
X155244Y26293D01*
X155245Y26299D01*
X155630D01*
X155609Y26110D01*
X155670Y25502D01*
X155792Y25259D01*
X156035Y24955D01*
Y24894D01*
X156461Y24529D01*
X156704Y24407D01*
X157130Y24346D01*
X157191Y24286D01*
X157920Y24346D01*
X157981Y24407D01*
X158225Y24468D01*
X158590Y24772D01*
X159015Y25259D01*
X159076Y25502D01*
X159137Y25563D01*
X159198Y25989D01*
X159137Y26597D01*
X159076Y26658D01*
X159015Y26901D01*
X158711Y27266D01*
Y27387D01*
X158590D01*
X158225Y27692D01*
X158103D01*
X158042Y27752D01*
X157677Y27813D01*
X157617Y27874D01*
X156887Y27813D01*
X156826Y27752D01*
X156583Y27692D01*
X156339Y27509D01*
X156278D01*
X155853Y27022D01*
X155670Y26658D01*
X155630Y26300D01*
X155245D01*
X155306Y26780D01*
X155549Y27266D01*
X155731Y27509D01*
X156218Y27935D01*
X156583Y28117D01*
X156948Y28178D01*
X157008Y28239D01*
X157799D01*
X157860Y28178D01*
X158225Y28117D01*
X158468Y27996D01*
X158772Y27752D01*
X158833D01*
X159259Y27266D01*
X159380Y27022D01*
X159441Y26780D01*
X159502Y26719D01*
X159563Y25624D01*
X159502Y25563D01*
X159441Y25259D01*
X159259Y24894D01*
X158833Y24407D01*
X158772D01*
G37*
G36*
G01X150987Y22887D02*
X150257Y22826D01*
X150196Y22765D01*
X149771Y22704D01*
X149710Y22644D01*
X149406Y22583D01*
X149224Y22461D01*
X148980Y22400D01*
X148372Y22096D01*
X148068Y21853D01*
X148007D01*
X147642Y21549D01*
X147581D01*
X146669Y20637D01*
X146608Y20697D01*
X146669Y21123D01*
X146730Y21184D01*
X146791Y21670D01*
X146852Y21731D01*
X146912Y22218D01*
X146973Y22279D01*
X147034Y22583D01*
Y22644D01*
X142412D01*
X142351Y22583D01*
X142290Y22096D01*
X142229Y22035D01*
X142169Y21488D01*
X142107Y21427D01*
X142047Y20941D01*
X141986Y20880D01*
X141925Y20393D01*
X141864Y20333D01*
X141804Y19785D01*
X141743Y19724D01*
X141682Y19238D01*
X141621Y19177D01*
X141560Y18691D01*
X141499Y18630D01*
X141439Y18143D01*
X141378Y18082D01*
X141317Y17535D01*
X141256Y17474D01*
X141195Y16987D01*
X141135Y16927D01*
X141074Y16440D01*
X141013Y16379D01*
X140952Y15832D01*
X140891Y15771D01*
X140830Y15285D01*
X140770Y15224D01*
X140709Y14737D01*
X140648Y14676D01*
X140587Y14129D01*
X140526Y14068D01*
X140465Y13581D01*
X140405Y13521D01*
X140344Y13034D01*
X140283Y12973D01*
X140222Y12487D01*
X140161Y12426D01*
X140100Y11879D01*
X140040Y11818D01*
X139979Y11331D01*
X139918Y11270D01*
X139857Y10784D01*
X139796Y10723D01*
X139736Y10176D01*
X139675Y10115D01*
X139614Y9689D01*
X144601D01*
X144662Y10054D01*
X144723Y10115D01*
X144783Y10662D01*
X144844Y10723D01*
X144905Y11209D01*
X144966Y11270D01*
X145027Y11757D01*
X145088Y11818D01*
X145148Y12304D01*
X145209Y12365D01*
X145270Y12852D01*
X145331Y12913D01*
X145392Y13460D01*
X145453Y13521D01*
X145513Y14007D01*
X145574Y14068D01*
X145635Y14555D01*
X145696Y14615D01*
X145757Y15102D01*
X145818Y15163D01*
X145878Y15650D01*
X145939Y15710D01*
X146000Y16136D01*
X146061Y16197D01*
X146122Y16501D01*
X146183Y16562D01*
X146243Y16805D01*
X146304Y16866D01*
X146365Y17109D01*
X146426Y17170D01*
X146487Y17413D01*
X146669Y17656D01*
X146730Y17839D01*
X146973Y18143D01*
Y18204D01*
X147399Y18691D01*
X147460D01*
X147885Y19055D01*
X148250Y19238D01*
X148737Y19298D01*
X148798Y19359D01*
X149406Y19298D01*
X149649Y19116D01*
X149771D01*
Y18994D01*
X149893Y18873D01*
X149953Y18508D01*
X150014Y18447D01*
X149953Y17717D01*
X149893Y17656D01*
X149831Y17048D01*
X149771Y16987D01*
X149710Y16440D01*
X149649Y16379D01*
X149588Y15893D01*
X149528Y15832D01*
X149467Y15285D01*
X149406Y15224D01*
X149345Y14737D01*
X149284Y14676D01*
X149224Y14190D01*
X149163Y14129D01*
X149102Y13581D01*
X149041Y13521D01*
X148980Y13034D01*
X148919Y12973D01*
X148859Y12426D01*
X148798Y12365D01*
X148737Y11879D01*
X148676Y11818D01*
X148615Y11331D01*
X148554Y11270D01*
X148494Y10723D01*
X148433Y10662D01*
X148372Y10176D01*
X148311Y10115D01*
X148250Y9689D01*
X153237D01*
X153298Y10176D01*
X153359Y10237D01*
X153420Y10723D01*
X153481Y10784D01*
X153542Y11331D01*
X153602Y11392D01*
X153663Y11879D01*
X153724Y11939D01*
X153785Y12487D01*
X153846Y12548D01*
X153907Y13034D01*
X153967Y13095D01*
X154028Y13581D01*
X154089Y13643D01*
X154150Y14190D01*
X154211Y14250D01*
X154271Y14737D01*
X154332Y14798D01*
X154393Y15345D01*
X154454Y15406D01*
X154515Y15893D01*
X154576Y15954D01*
X154636Y16501D01*
X154697Y16562D01*
X154758Y17048D01*
X154819Y17109D01*
X154880Y17656D01*
X154941Y17717D01*
X155001Y18326D01*
X155062Y18386D01*
X155123Y19116D01*
X155184Y19177D01*
X155123Y20758D01*
X155062Y20819D01*
X155001Y21062D01*
X154941Y21123D01*
Y21245D01*
X154758Y21488D01*
Y21549D01*
X154332Y22035D01*
X153846Y22461D01*
X153359Y22704D01*
X153055Y22765D01*
X152994Y22826D01*
X152386Y22887D01*
X152325Y22948D01*
X151048D01*
X150987Y22887D01*
G37*
G36*
G01X161208Y29211D02*
Y5589D01*
X287192D01*
Y29211D01*
X161208D01*
G37*
G36*
G01X158285Y25137D02*
X158407Y24894D01*
X157860D01*
X157799Y24955D01*
X157617Y25380D01*
X157434Y25624D01*
Y25745D01*
X157252Y25806D01*
X156826Y25867D01*
Y24894D01*
X156400D01*
Y26690D01*
X156826D01*
Y26232D01*
X157130D01*
X157738Y26293D01*
X157799Y26475D01*
X157738Y26840D01*
X157556D01*
X157495Y26901D01*
X156826D01*
Y26691D01*
X156400D01*
Y27266D01*
X157556D01*
X157920Y27205D01*
X158164Y27022D01*
X158225Y26780D01*
X158285Y26719D01*
X158225Y26354D01*
X157981Y26050D01*
X157738Y25989D01*
X157677Y25928D01*
X157799Y25806D01*
X157860D01*
X157920Y25745D01*
X158042Y25563D01*
X158103Y25380D01*
X158285Y25137D01*
G37*
G36*
G01X465000Y22400D02*
Y24200D01*
X469500D01*
Y22400D01*
X465000D01*
G37*
G36*
G01X456000Y17900D02*
Y19700D01*
X459600D01*
Y17900D01*
X456000D01*
G37*
G36*
G01X465000D02*
Y19700D01*
X467700D01*
Y17900D01*
X465000D01*
G37*
G36*
G01X459600Y13400D02*
Y24200D01*
X461400D01*
Y13400D01*
X459600D01*
G37*
G36*
G01X463200D02*
Y24200D01*
X465000D01*
Y13400D01*
X463200D01*
G37*
G36*
G01X454200D02*
Y24200D01*
X456000D01*
Y13400D01*
X454200D01*
G37*
G36*
G01X533311Y19900D02*
G02I-11811J0D01*
G37*
G36*
G01X543600Y11700D02*
Y6700D01*
X563600D01*
Y11700D01*
X543600D01*
G37*
%LPC*%
G75*
G36*
G01X521500Y9270D02*
X523575Y9475D01*
X525570Y10080D01*
X527405Y11060D01*
X528474Y11940D01*
X526034Y14380D01*
X525604D01*
X525506Y14388D01*
X524805Y14600D01*
X524480Y14775D01*
Y14380D01*
X522880D01*
Y17535D01*
X520163Y20252D01*
X519755Y19920D01*
X519119Y19579D01*
X518463Y19380D01*
X515905D01*
Y14380D01*
X514335D01*
Y26080D01*
X513540Y26874D01*
X512660Y25805D01*
X511680Y23970D01*
X511075Y21975D01*
X510870Y19900D01*
X511075Y17825D01*
X511680Y15830D01*
X512660Y13995D01*
X513985Y12385D01*
X515595Y11060D01*
X517430Y10080D01*
X519425Y9475D01*
X521500Y9270D01*
G37*
G36*
G01X529459Y12925D02*
X530340Y13995D01*
X531320Y15830D01*
X531925Y17825D01*
X532130Y19900D01*
X531925Y21975D01*
X531320Y23970D01*
X530340Y25805D01*
X529015Y27415D01*
X527405Y28740D01*
X525570Y29720D01*
X523575Y30325D01*
X521500Y30530D01*
X519425Y30325D01*
X517430Y29720D01*
X515595Y28740D01*
X514524Y27858D01*
X515766Y26615D01*
X518155D01*
X518429Y26580D01*
X519120Y26370D01*
X519755Y26030D01*
X520315Y25575D01*
X520770Y25015D01*
X521110Y24380D01*
X521320Y23690D01*
X521390Y22975D01*
X521320Y22260D01*
X521110Y21570D01*
X521006Y21377D01*
X522880Y19503D01*
Y26420D01*
X524480D01*
Y22365D01*
X524805Y22540D01*
X525500Y22750D01*
X526225Y22820D01*
X526950Y22750D01*
X527645Y22540D01*
X528285Y22195D01*
X528845Y21735D01*
X529305Y21175D01*
X529650Y20535D01*
X529859Y19842D01*
X529930Y19115D01*
Y18025D01*
X529860Y17300D01*
X529650Y16605D01*
X529305Y15965D01*
X528845Y15405D01*
X528285Y14945D01*
X527735Y14649D01*
X529459Y12925D01*
G37*
G36*
G01X526535Y15849D02*
X526655Y15860D01*
X527071Y15990D01*
X527453Y16192D01*
X527789Y16469D01*
X528062Y16803D01*
X528263Y17184D01*
X528391Y17598D01*
X528430Y18025D01*
Y19115D01*
X528392Y19545D01*
X528260Y19960D01*
X528060Y20340D01*
X527785Y20675D01*
X527450Y20951D01*
X527068Y21151D01*
X526653Y21280D01*
X526226Y21320D01*
X525796Y21280D01*
X525380Y21150D01*
X525000Y20950D01*
X524665Y20675D01*
X524480Y20450D01*
Y17903D01*
X526535Y15849D01*
G37*
G36*
G01X515905Y20955D02*
X518515D01*
X518545Y20965D01*
X518925Y21165D01*
X519107Y21308D01*
X515905Y24510D01*
Y20955D01*
G37*
G36*
G01X519846Y22536D02*
X519850Y22550D01*
X519890Y22975D01*
X519850Y23400D01*
X519725Y23805D01*
X519525Y24185D01*
X519255Y24515D01*
X518925Y24785D01*
X518545Y24985D01*
X518460Y25015D01*
X517366D01*
X519846Y22536D01*
G37*
%LPD*%
G75*
G54D10*
G01X-23515Y-108314D02*
X-55515D01*
G01X-23515Y-124314D02*
Y-204314D01*
G01D02*
X1177585D01*
G01X-27515Y-108314D02*
G02I-12000J0D01*
G01X-39515Y-124314D02*
Y-92314D01*
G01X-23515Y-124314D02*
X1177585D01*
G01X-23515Y-159814D02*
X1177585D01*
G01X-32665Y-108314D02*
G02I-6850J0D01*
G01X48443Y58055D02*
Y52755D01*
X58643D01*
Y58055D01*
G01X172656D02*
Y52755D01*
X182856D01*
Y58055D01*
G01X318500Y35650D02*
Y3650D01*
X446300D01*
Y35600D01*
X416500Y35650D01*
X318500D01*
G01X296869Y58055D02*
Y52755D01*
X307069D01*
Y58055D01*
G01X390085Y-124314D02*
Y-204314D01*
G01X421081Y58055D02*
Y52755D01*
X431281D01*
Y58055D01*
G01X527585Y-124314D02*
Y-204314D01*
G01X545294Y58055D02*
Y52755D01*
X555494D01*
Y58055D01*
G01X642585Y-124314D02*
Y-204314D01*
G01X669506Y58055D02*
Y52755D01*
X679706D01*
Y58055D01*
G01X810085Y-124314D02*
Y-204314D01*
G01X980085Y-124314D02*
Y-204314D01*
G01X1177585Y-124314D02*
Y-204314D01*
G01X1205585Y-108314D02*
G02I-12000J0D01*
G01X1200435D02*
G02I-6850J0D01*
G01X1209585D02*
X1177585D01*
G01X1193585Y-124314D02*
Y-92314D01*
G54D11*
G01X4724Y39370D02*
X29921D01*
G01X4724Y130709D02*
X29921D01*
G01X4724Y174016D02*
X29921D01*
G01X4724Y265355D02*
X29921D01*
G01X4724Y308662D02*
X29921D01*
G01X4724Y400001D02*
X29921D01*
G01Y443308D02*
X4724D01*
G01X29921Y534647D02*
X4724D01*
G01Y577954D02*
X29921D01*
G01Y669293D02*
X4724D01*
G01X29921Y712600D02*
X4724D01*
G01X29921Y803939D02*
X4724D01*
G01Y847246D02*
X29921D01*
G01X72639Y113780D02*
Y88583D01*
G01Y248426D02*
Y223229D01*
G01Y383072D02*
Y357875D01*
G01Y517718D02*
Y492521D01*
G01Y652364D02*
Y627167D01*
G01Y787010D02*
Y761813D01*
G01Y921656D02*
Y896459D01*
G01X206102Y71654D02*
X180905D01*
G01X206102Y79528D02*
X180905D01*
G01X206102Y206300D02*
X180905D01*
G01X206102Y214174D02*
X180905D01*
G01X206102Y340946D02*
X180905D01*
G01X206102Y348820D02*
X180905D01*
G01X206102Y475592D02*
X180905D01*
G01X206102Y483466D02*
X180905D01*
G01Y610238D02*
X206102D01*
G01X180905Y618112D02*
X206102D01*
G01X180905Y744884D02*
X206102D01*
G01X180905Y752758D02*
X206102D01*
G01X180905Y879530D02*
X206102D01*
G01X180905Y887404D02*
X206102D01*
G01X196309Y122835D02*
X221506D01*
G01X196309Y130709D02*
X221506D01*
G01X196309Y257481D02*
X221506D01*
G01X196309Y265355D02*
X221506D01*
G01X196309Y392127D02*
X221506D01*
G01X196309Y400001D02*
X221506D01*
G01X196309Y526773D02*
X221506D01*
G01X196309Y534647D02*
X221506D01*
G01X196309Y661419D02*
X221506D01*
G01X196309Y669293D02*
X221506D01*
G01X196309Y796065D02*
X221506D01*
G01X196309Y803939D02*
X221506D01*
G01X325788Y39370D02*
X350985D01*
G01Y79528D02*
X325788D01*
G01Y174016D02*
X350985D01*
G01X325788Y214174D02*
X350985D01*
G01X325788Y308662D02*
X350985D01*
G01X325788Y348820D02*
X350985D01*
G01X325788Y443308D02*
X350985D01*
G01X325788Y483466D02*
X350985D01*
G01X325788Y577954D02*
X350985D01*
G01X325788Y618112D02*
X350985D01*
G01Y712600D02*
X325788D01*
G01Y752758D02*
X350985D01*
G01X325788Y847246D02*
X350985D01*
G01X325788Y887404D02*
X350985D01*
G01X413091Y122835D02*
X387894D01*
G01X413091Y130709D02*
X387894D01*
G01X413091Y257481D02*
X387894D01*
G01X413091Y265355D02*
X387894D01*
G01Y392127D02*
X413091D01*
G01X387894Y400001D02*
X413091D01*
G01X387894Y526773D02*
X413091D01*
G01X387894Y534647D02*
X413091D01*
G01Y661419D02*
X387894D01*
G01X413091Y669293D02*
X387894D01*
G01Y796065D02*
X413091D01*
G01X387894Y803939D02*
X413091D01*
G01X475197Y39370D02*
X450000D01*
G01X475197Y79528D02*
X450000D01*
G01Y214174D02*
X475197D01*
G01X450000Y174016D02*
X475197D01*
G01X450000Y308662D02*
X475197D01*
G01X450000Y348820D02*
X475197D01*
G01X450000Y443308D02*
X475197D01*
G01X450000Y483466D02*
X475197D01*
G01Y577954D02*
X450000D01*
G01X475197Y618112D02*
X450000D01*
G01X475197Y712600D02*
X450000D01*
G01Y752758D02*
X475197D01*
G01Y847246D02*
X450000D01*
G01X475197Y887404D02*
X450000D01*
G01X620080Y39370D02*
X594883D01*
G01X620080Y47244D02*
X594883D01*
G01X579479Y122835D02*
X604676D01*
G01X579479Y130709D02*
X604676D01*
G01X594883Y174016D02*
X620080D01*
G01X594883Y181890D02*
X620080D01*
G01X579479Y257481D02*
X604676D01*
G01X620080Y308662D02*
X594883D01*
G01X579479Y265355D02*
X604676D01*
G01X620080Y316536D02*
X594883D01*
G01X604676Y392127D02*
X579479D01*
G01X604676Y400001D02*
X579479D01*
G01X620080Y443308D02*
X594883D01*
G01X620080Y451182D02*
X594883D01*
G01X579479Y526773D02*
X604676D01*
G01X579479Y534647D02*
X604676D01*
G01X594883Y585828D02*
X620080D01*
G01Y577954D02*
X594883D01*
G01X604676Y661419D02*
X579479D01*
G01X604676Y669293D02*
X579479D01*
G01X594883Y712600D02*
X620080D01*
G01X594883Y720474D02*
X620080D01*
G01X604676Y796065D02*
X579479D01*
G01X604676Y803939D02*
X579479D01*
G01X620080Y847246D02*
X594883D01*
G01X620080Y855120D02*
X594883D01*
G01X720079Y39370D02*
X701969D01*
G01Y79528D02*
X720079D01*
G01Y214174D02*
X701969D01*
G01Y174016D02*
X720079D01*
G01Y308662D02*
X701969D01*
G01Y348820D02*
X720079D01*
G01X701969Y443308D02*
X720079D01*
G01X701969Y483466D02*
X720079D01*
G01X701969Y577954D02*
X720079D01*
G01X701969Y618112D02*
X720079D01*
G01X701969Y712600D02*
X720079D01*
G01Y752758D02*
X701969D01*
G01Y847246D02*
X720079D01*
G01X701969Y887404D02*
X720079D01*
G01X728346Y5118D02*
Y30315D01*
G01Y139764D02*
Y164961D01*
G01Y299607D02*
Y274410D01*
G01Y434253D02*
Y409056D01*
G01Y568899D02*
Y543702D01*
G01Y703545D02*
Y678348D01*
G01Y838191D02*
Y812995D01*
G01X771064Y79528D02*
X796261D01*
G01X771064Y122835D02*
X796261D01*
G01X771064Y214174D02*
X796261D01*
G01X771064Y257481D02*
X796261D01*
G01X771064Y348820D02*
X796261D01*
G01X771064Y392127D02*
X796261D01*
G01X771064Y483466D02*
X796261D01*
G01X771064Y526773D02*
X796261D01*
G01Y618112D02*
X771064D01*
G01Y661419D02*
X796261D01*
G01X771064Y752758D02*
X796261D01*
G01X771064Y796065D02*
X796261D01*
G01Y887404D02*
X771064D01*
G54D12*
G01X472300Y19700D02*
G03I-10900J0D01*
G54D13*
G01X546770Y16790D02*
X546110D01*
G01X546210Y16880D02*
X546870D01*
G01X546960Y16990D02*
X546310D01*
G01X546410Y17080D02*
X547060D01*
G01X547160Y17190D02*
X546500D01*
G01X546600Y17290D02*
X547250D01*
G01X547350Y17380D02*
X546700D01*
G01X546790Y17490D02*
X547450D01*
G01X547540Y17580D02*
X546890D01*
G01X546980Y17690D02*
X547640D01*
G01X547740Y17790D02*
X547080D01*
G01X547180Y17880D02*
X547830D01*
G01X547930Y17990D02*
X547285D01*
G01X547280D02*
X547330D01*
G01X547370Y18080D02*
X547410D01*
G01X547370D02*
X548020D01*
G01X548120Y18190D02*
X547470D01*
G01X547570Y18290D02*
X548220D01*
G01X548320Y18380D02*
X547660D01*
G01X547760Y18490D02*
X548410D01*
G01X548510Y18580D02*
X547850D01*
G01X547950Y18690D02*
X548610D01*
G01X548700Y18790D02*
X548050D01*
G01X548150Y18880D02*
X548800D01*
G01X548890Y18990D02*
X548240D01*
G01X548340Y19080D02*
X548990D01*
G01X549090Y19190D02*
X548430D01*
G01X548530Y19290D02*
X549190D01*
G01X549280Y19380D02*
X548630D01*
G01X548720Y19490D02*
X549380D01*
G01X549570Y19690D02*
X548920D01*
G01X549110Y19880D02*
X549760D01*
G01X549780Y27880D02*
X550220Y22730D01*
G01X550230Y22690D02*
X550700D01*
G01X550710Y22490D02*
X550240D01*
G01X550260Y22290D02*
X550730D01*
G01X550750Y22080D02*
X550280D01*
G01X550300Y21880D02*
X550770D01*
G01X550810Y21790D02*
X550310D01*
G01X550320Y21140D02*
X550220Y21030D01*
G01X550350Y21210D02*
X550320Y21140D01*
G01X550170Y20990D02*
X550860D01*
G01Y20790D02*
X549980D01*
G01X549790Y20580D02*
X550880D01*
G01X550240Y20380D02*
X549590D01*
G01X549500Y20290D02*
X550150D01*
G01X550050Y20190D02*
X549400D01*
G01X549300Y20080D02*
X549960D01*
G01X549860Y19990D02*
X549210D01*
G01X549020Y19790D02*
X549670D01*
G01X549470Y19580D02*
X548820D01*
G01X550200Y22990D02*
X550670D01*
G01X550650Y23190D02*
X550190D01*
G01X550170Y23380D02*
X550640D01*
G01X550620Y23580D02*
X550150D01*
G01X550130Y23790D02*
X550600D01*
G01X550590Y23990D02*
X550120D01*
G01X550590Y23880D02*
X550130D01*
G01X550140Y23690D02*
X550610D01*
G01X550630Y23490D02*
X550160D01*
G01X550180Y23290D02*
X550650D01*
G01X550660Y23080D02*
X550190D01*
G01X550210Y22880D02*
X550680D01*
G01X550690Y22790D02*
X550220D01*
G01X550350Y21270D02*
Y21210D01*
G01X550220Y22730D02*
X550350Y21270D01*
G01X550340Y21190D02*
X551020D01*
G01X550870Y21010D02*
X550850Y20940D01*
G01X550920Y21090D02*
X550870Y21010D01*
G01X550850Y20880D02*
X550080D01*
G01X549890Y20690D02*
X550870D01*
G01X550890Y20380D02*
X550390D01*
G01X550360Y20420D02*
X550260Y20400D01*
G01X550630Y17980D02*
X550740D01*
G01X550630Y17990D02*
Y17980D01*
G01X550430Y20340D02*
X550630Y17990D01*
G01X550360Y20420D02*
X550430Y20340D01*
G01X550730Y18080D02*
X550620D01*
G01X550625D02*
X556220D01*
G01X556285Y17990D02*
X550630D01*
G01X550870Y16940D02*
X551760D01*
G01X550830Y16980D02*
X550870Y16940D01*
G01X550830Y17660D02*
Y16980D01*
G01X550800Y17730D02*
X550830Y17660D01*
G01X550650Y17890D02*
X550800Y17730D01*
G01X550640Y17910D02*
X550650Y17890D01*
G01X550630Y17970D02*
X550640Y17910D01*
G01X551800Y16990D02*
X550830D01*
G01Y17190D02*
X551800D01*
G01Y17380D02*
X550830D01*
G01Y17580D02*
X551800D01*
G01X551080Y18290D02*
X550610D01*
G01X550590Y18380D02*
X551060D01*
G01X551050Y18580D02*
X550580D01*
G01X550560Y18790D02*
X551030D01*
G01X551010Y18990D02*
X550540D01*
G01X550530Y19190D02*
X551000D01*
G01X550980Y19380D02*
X550510D01*
G01X550490Y19580D02*
X550960D01*
G01X550950Y19790D02*
X550480D01*
G01X550460Y19990D02*
X550930D01*
G01X550910Y20190D02*
X550450D01*
G01X550340Y21380D02*
X551210D01*
G01X551400Y21580D02*
X550320D01*
G01X550290Y21990D02*
X550760D01*
G01X550770Y21840D02*
X550320Y27130D01*
G01X550710Y22580D02*
X550240D01*
G01X550250Y22380D02*
X550720D01*
G01X550740Y22190D02*
X550270D01*
G01X550840Y21750D02*
X550940Y21780D01*
G01X550770Y21840D02*
X550840Y21750D01*
G01X550750Y17790D02*
X556530D01*
G01X551070Y18360D02*
X550850Y20940D01*
G01X551070Y18290D02*
Y18360D01*
G01X551170Y18200D02*
X551070Y18290D01*
G01X555270Y18200D02*
X551170D01*
G01X550920Y21080D02*
X550270D01*
G01X550350Y21290D02*
X551110D01*
G01X550930Y21090D02*
X550920D01*
G01X550930Y21100D02*
Y21090D01*
G01Y21100D02*
X553520Y23790D01*
G01X553330Y23580D02*
X552690D01*
G01X552490Y23380D02*
X553140D01*
G01X552950Y23190D02*
X552300D01*
G01X552110Y22990D02*
X552750D01*
G01X552660Y22880D02*
X552010D01*
G01X552060Y22940D02*
X550940Y21780D01*
G01X550950Y21790D02*
X551590D01*
G01X551500Y21690D02*
X550320D01*
G01X550330Y21490D02*
X551310D01*
G01X551050Y21880D02*
X551690D01*
G01X551790Y21990D02*
X551150D01*
G01X551240Y22080D02*
X551890D01*
G01X551980Y22190D02*
X551340D01*
G01X551430Y22290D02*
X552080D01*
G01X552170Y22380D02*
X551530D01*
G01X551630Y22490D02*
X552270D01*
G01X552370Y22580D02*
X551720D01*
G01X551820Y22690D02*
X552460D01*
G01X552560Y22790D02*
X551910D01*
G01X550890Y20490D02*
X549690D01*
G01X550430Y20290D02*
X550900D01*
G01X550920Y20080D02*
X550450D01*
G01X550470Y19880D02*
X550940D01*
G01X550950Y19690D02*
X550480D01*
G01X550500Y19490D02*
X550970D01*
G01X550990Y19290D02*
X550520D01*
G01X550540Y19080D02*
X551000D01*
G01X551020Y18880D02*
X550560D01*
G01X550570Y18690D02*
X551040D01*
G01X551060Y18490D02*
X550590D01*
G01X550820Y17690D02*
X551870D01*
G01X551800Y16980D02*
X551760Y16940D01*
G01X551800Y17620D02*
Y16980D01*
G01X551900Y17720D02*
X551800Y17620D01*
G01Y17080D02*
X550830D01*
G01Y17290D02*
X551800D01*
G01Y17490D02*
X550830D01*
G01X555370Y18670D02*
Y18680D01*
G01X555360Y18600D02*
X555370Y18670D01*
G01X555360Y18340D02*
Y18600D01*
G01X555370Y18320D02*
X555360Y18340D01*
G01X555270Y18200D02*
X555370Y18320D01*
G01Y18690D02*
X556140D01*
G01X556100Y18490D02*
X555360D01*
G01X555340Y18290D02*
X556140D01*
G01X556680Y21220D02*
X553980Y24120D01*
G01X553220Y24130D02*
X552060Y22940D01*
G01X552210Y23080D02*
X552850D01*
G01X553040Y23290D02*
X552400D01*
G01X552590Y23490D02*
X553240D01*
G01X553430Y23690D02*
X552780D01*
G01X553670Y23790D02*
X555350Y21970D01*
G01X553520Y23790D02*
X553670D01*
G01X552880D02*
X553520D01*
G01X555340Y21990D02*
X555970D01*
G01X555780Y22190D02*
X555150D01*
G01X554970Y22380D02*
X555600D01*
G01X555410Y22580D02*
X554780D01*
G01X554690Y22690D02*
X555320D01*
G01X555220Y22790D02*
X554590D01*
G01X554500Y22880D02*
X555130D01*
G01X555040Y22990D02*
X554410D01*
G01X554320Y23080D02*
X554950D01*
G01X554850Y23190D02*
X554220D01*
G01X554130Y23290D02*
X554760D01*
G01X554670Y23380D02*
X554040D01*
G01X553950Y23490D02*
X554580D01*
G01X554480Y23580D02*
X553850D01*
G01X553760Y23690D02*
X554390D01*
G01X554300Y23790D02*
X553650D01*
G01X554110Y23990D02*
X553080D01*
G01X552980Y23880D02*
X554200D01*
G01X555500Y22490D02*
X554870D01*
G01X555060Y22290D02*
X555690D01*
G01X555870Y22080D02*
X555240D01*
G01X555430Y21880D02*
X556060D01*
G01X556150Y21790D02*
X555520D01*
G01X555610Y21690D02*
X556250D01*
G01X556340Y21580D02*
X555710D01*
G01X555800Y21490D02*
X556430D01*
G01X556620Y21290D02*
X555990D01*
G01X556170Y21080D02*
X557310D01*
G01X557300Y20990D02*
X556270D01*
G01X555410Y18860D02*
X555370Y18680D01*
G01X555410Y18870D02*
Y18860D01*
G01X555520Y19180D02*
X555410Y18870D01*
G01X555530Y19190D02*
X555520Y19180D01*
G01X555740Y19500D02*
X555530Y19190D01*
G01X555750Y19510D02*
X555740Y19500D01*
G01X555990Y19730D02*
X555750Y19510D01*
G01X556000Y19730D02*
X555990D01*
G01X556120Y19810D02*
X556000Y19730D01*
G01X556130Y19820D02*
X556120Y19810D01*
G01X556190Y19850D02*
X556130Y19820D01*
G01X556350Y19920D02*
X556190Y19850D01*
G01X555360Y18580D02*
X556120D01*
G01X556160Y18190D02*
X550610D01*
G01X556150Y18210D02*
X556160Y18190D01*
G01X556100Y18470D02*
X556150Y18210D01*
G01X556100Y18480D02*
Y18470D01*
G01Y18500D02*
Y18480D01*
G01X550650Y17880D02*
X556390D01*
G01X556310Y17950D02*
X556250Y18040D01*
G01X556320Y17940D02*
X556310Y17950D01*
G01X556330Y17930D02*
X556320Y17940D01*
G01X556170Y18180D02*
X556160Y18190D01*
G01X556250Y18050D02*
X556170Y18180D01*
G01X556120Y18380D02*
X555360D01*
G01X555390Y18790D02*
X556160D01*
G01X556150Y18760D02*
X556100Y18500D01*
G01X556160Y18780D02*
X556150Y18760D01*
G01X556380Y18510D02*
X556390Y18530D01*
G01X556330Y19040D02*
X556550Y19200D01*
G01X556320Y19030D02*
X556330Y19040D01*
G01X556310Y19010D02*
X556320Y19030D01*
G01X556170Y18800D02*
X556310Y19010D01*
G01X556160Y18780D02*
X556170Y18800D01*
G01X556390Y19080D02*
X555490D01*
G01X555450Y18990D02*
X556290D01*
G01X556220Y18880D02*
X555410D01*
G01X555590Y19290D02*
X556850D01*
G01X556260Y19880D02*
X557930D01*
G01X558020Y19790D02*
X556080D01*
G01X555840Y19580D02*
X558210D01*
G01X558390Y19380D02*
X555670D01*
G01X556250Y17990D02*
X556290D01*
G01X556330Y17930D02*
X556550Y17770D01*
G01X556120Y17190D02*
X557670D01*
G01X557830Y17290D02*
X555940D01*
G01X555500Y17720D02*
X551900D01*
G01X555580Y17690D02*
X555500Y17720D01*
G01X555590Y17680D02*
X555580Y17690D01*
G01X555590Y17670D02*
Y17680D01*
G01X555630Y17600D02*
X555590Y17670D01*
G01X555640Y17600D02*
X555630D01*
G01X555650Y17590D02*
X555640Y17600D01*
G01X555720Y17490D02*
X555650Y17590D01*
G01X555730Y17480D02*
X555720Y17490D01*
G01X555960Y17260D02*
X555730Y17480D01*
G01Y17490D02*
X558070D01*
G01X555980Y17250D02*
X555960Y17260D01*
G01X556780Y16950D02*
X557120Y16960D01*
G01X556770Y16950D02*
X556780D01*
G01X556760D02*
X556770D01*
G01X556600Y16970D02*
X556760Y16950D01*
G01X556580Y16970D02*
X556600D01*
G01X555980Y17250D02*
X556580Y16970D01*
G01X557230Y16990D02*
X556560D01*
G01Y17760D02*
X556550Y17770D01*
G01X556580Y17760D02*
X556560D01*
G01X556750Y17700D02*
X556580Y17760D01*
G01X556970Y17690D02*
X556990D01*
G01X556840D02*
X556970D01*
G01X556770Y17700D02*
X556840Y17690D01*
G01X556750Y17700D02*
X556770D01*
G01X556410Y18320D02*
X556380Y18510D01*
G01X556420Y18290D02*
X556410Y18320D01*
G01X556590Y18070D02*
X556420Y18290D01*
G01X556610Y18060D02*
X556590Y18070D01*
G01X556780Y17980D02*
X556610Y18060D01*
G01X556790Y17980D02*
X556780D01*
G01X556830Y17970D02*
X556790Y17980D01*
G01X556890Y17970D02*
X556830D01*
G01X556910D02*
X556890D01*
G01X556940Y19000D02*
X556950D01*
G01X556850D02*
X556940D01*
G01X556830Y18990D02*
X556850Y19000D01*
G01X556520Y18830D02*
X556830Y18990D01*
G01X556500Y18810D02*
X556520Y18830D01*
G01X556390Y18530D02*
X556500Y18810D01*
G01X556560Y19210D02*
X556550Y19200D01*
G01X556580Y19210D02*
X556560D01*
G01X556750Y19270D02*
X556580Y19210D01*
G01X556770Y19270D02*
X556750D01*
G01X556840Y19280D02*
X556770Y19270D01*
G01X556860Y19290D02*
X556840Y19280D01*
G01X556920Y19290D02*
X556860D01*
G01X556950Y19280D02*
X556920Y19290D01*
G01X556530Y19190D02*
X555530D01*
G01X556440Y18670D02*
X557380D01*
G01X557400Y18470D02*
X556390D01*
G01X556440Y18270D02*
X557350D01*
G01X557170Y18070D02*
X556600D01*
G01X556910Y17970D02*
X557040Y17990D01*
G01X557240Y18860D02*
X556590D01*
G01X556990Y19280D02*
X557190Y19230D01*
G01X556950Y19280D02*
X556990D01*
G01X556440Y19950D02*
X556350Y19920D01*
G01X556450Y19960D02*
X556440Y19950D01*
G01X556590Y19990D02*
X556450Y19960D01*
G01X556670Y20010D02*
X556590Y19990D01*
G01X556450Y20790D02*
X555350Y21970D01*
G01X556710Y20510D02*
X556450Y20790D01*
G01X556740Y20460D02*
X556710Y20510D01*
G01X556770Y20310D02*
X556740Y20460D01*
G01X556780Y20290D02*
X556770Y20310D01*
G01X556780Y20270D02*
Y20290D01*
G01X556760Y20100D02*
X556780Y20270D01*
G01X556760Y20090D02*
Y20100D01*
G01X556670Y20010D02*
X556760Y20090D01*
G01X555890Y21380D02*
X556530D01*
G01X556850Y21280D02*
X557360Y27510D01*
G01X556790Y21200D02*
X556850Y21280D01*
G01X556680Y21220D02*
X556790Y21200D01*
G01X557020Y23290D02*
X557480D01*
G01X557470Y23080D02*
X557000D01*
G01X556980Y22880D02*
X557450D01*
G01X557440Y22690D02*
X556970D01*
G01X556950Y22490D02*
X557420D01*
G01X557410Y22290D02*
X556940D01*
G01X556920Y22080D02*
X557390D01*
G01X557370Y21880D02*
X556910D01*
G01X556890Y21690D02*
X557350D01*
G01X557340Y21490D02*
X556870D01*
G01X556850Y21290D02*
X557320D01*
G01X557280Y20790D02*
X556450D01*
G01X556640Y20580D02*
X557280D01*
G01X557460Y20380D02*
X556760D01*
G01X556770Y20190D02*
X557650D01*
G01X557070Y23880D02*
X557540D01*
G01X557520Y23690D02*
X557050D01*
G01X557040Y23490D02*
X557500D01*
G01X557490Y23380D02*
X557030D01*
G01X557010Y23190D02*
X557480D01*
G01X557460Y22990D02*
X556990D01*
G01X556980Y22790D02*
X557450D01*
G01X557430Y22580D02*
X556960D01*
G01X556950Y22380D02*
X557410D01*
G01X557400Y22190D02*
X556930D01*
G01X556910Y21990D02*
X557380D01*
G01X557360Y21790D02*
X556900D01*
G01X556880Y21580D02*
X557350D01*
G01X557330Y21380D02*
X556860D01*
G01X557320Y21190D02*
X556080D01*
G01X556360Y20880D02*
X557290D01*
G01X557280Y20690D02*
X556550D01*
G01X556720Y20490D02*
X557360D01*
G01X557300Y20550D02*
X558260Y19530D01*
G01X558580Y19190D02*
X557250D01*
G01X557230Y19210D02*
X557190Y19230D01*
G01X557230Y19210D02*
X557540Y18950D01*
G01X557310Y18770D02*
X556480D01*
G01X556400Y18570D02*
X557390D01*
G01X557200Y18900D02*
X556950Y19000D01*
G01X557220Y18890D02*
X557200Y18900D01*
G01X557370Y18690D02*
X557220Y18890D01*
G01X557380Y18660D02*
X557370Y18690D01*
G01X557040Y18970D02*
X556770D01*
G01X557060Y17990D02*
X557040D01*
G01X557280Y18130D02*
X557060Y17990D01*
G01X557290Y18150D02*
X557280Y18130D01*
G01X557400Y18380D02*
X557290Y18150D01*
G01X557410Y18400D02*
X557400Y18380D01*
G01X557380Y18660D02*
X557410Y18400D01*
G01X557250Y17790D02*
X558270D01*
G01X557130Y16960D02*
X557120D01*
G01X557420Y17030D02*
X557130Y16960D01*
G01X557430Y17040D02*
X557420Y17030D01*
G01X557940Y17350D02*
X557430Y17040D01*
G01X557190Y17740D02*
X557230Y17760D01*
G01X556990Y17690D02*
X557190Y17740D01*
G01X557300Y18170D02*
X556520D01*
G01X556400Y18360D02*
X557400D01*
G01X557290Y20570D02*
X557270Y20640D01*
G01X557300Y20560D02*
X557290Y20570D01*
G01X557300Y20550D02*
Y20560D01*
G01X557840Y27570D02*
X557270Y20640D01*
G01X557550Y20290D02*
X556780D01*
G01X556750Y20080D02*
X557740D01*
G01X557830Y19990D02*
X556560D01*
G01X555950Y19690D02*
X558110D01*
G01X558300Y19490D02*
X555730D01*
G01X555580Y17690D02*
X558210D01*
G01X558030Y17440D02*
X557940Y17350D01*
G01X558090Y17510D02*
X558030Y17440D01*
G01X558220Y17700D02*
X558090Y17510D01*
G01X557980Y17380D02*
X555830D01*
G01X555650Y17580D02*
X558140D01*
G01X558340Y17950D02*
X558400Y18120D01*
G01X558300Y17850D02*
X558340Y17950D01*
G01X558300Y17840D02*
Y17850D01*
G01X558230Y17710D02*
X558300Y17840D01*
G01X558220Y17700D02*
X558230Y17710D01*
G01X558390Y18080D02*
X557575D01*
G01X557580D02*
X557640D01*
G01X557540Y18020D02*
X557230Y17760D01*
G01X557570Y18070D02*
X557540Y18020D01*
G01X557370Y17880D02*
X558320D01*
G01X558350Y17990D02*
X557560D01*
G01X558320D02*
X558350D01*
G01X557570Y18900D02*
X557540Y18950D01*
G01X557690Y18510D02*
X557570Y18900D01*
G01X557690Y18450D02*
Y18510D01*
G01X557570Y18070D02*
X557690Y18450D01*
G01X557500Y18990D02*
X558760D01*
G01X558950Y18790D02*
X557610D01*
G01X557670Y18580D02*
X559130D01*
G01X558430Y18380D02*
X557670D01*
G01X557610Y18190D02*
X558410D01*
G01X557500Y17080D02*
X556340D01*
G01X557040Y23580D02*
X557510D01*
G01X557530Y23790D02*
X557060D01*
G01X557080Y23990D02*
X557540D01*
G01X558480Y19290D02*
X556930D01*
G01X557370Y19080D02*
X558670D01*
G01X558850Y18880D02*
X557580D01*
G01X557630Y18690D02*
X559040D01*
G01X559230Y18490D02*
X558540D01*
G01X558400Y18140D02*
Y18120D01*
G01X558440Y18410D02*
X558400Y18140D01*
G01X558500Y18490D02*
X558440Y18410D01*
G01X558420Y18290D02*
X557640D01*
G01X558500Y18490D02*
X558610Y18470D01*
G01X557690Y18490D02*
X558500D01*
G01X558690Y18380D02*
X559320D01*
G01X559410Y18290D02*
X558780D01*
G01X558870Y18190D02*
X559510D01*
G01X559560Y18080D02*
X559600D01*
G01X559610D02*
X558970D01*
G01X559060Y17990D02*
X559695D01*
G01X559690D02*
X559640D01*
G01X559795Y17880D02*
X559150D01*
G01X559240Y17790D02*
X559880D01*
G01X559970Y17690D02*
X559335D01*
G01X559435Y17580D02*
X560070D01*
G01X560160Y17490D02*
X559520D01*
G01X559625Y17380D02*
X560250D01*
G01X560350Y17290D02*
X559710D01*
G01X559800Y17190D02*
X560440D01*
G01X560530Y17080D02*
X559890D01*
G01X559980Y16990D02*
X560630D01*
G01X560810Y16790D02*
X560170D01*
G01X560080Y16880D02*
X560720D01*
G01X560900Y16690D02*
X560260D01*
G01X560360Y16580D02*
X561000D01*
G01X561090Y16490D02*
X560450D01*
G01X560540Y16380D02*
X561180D01*
G01X561280Y16290D02*
X560630D01*
G01X560730Y16190D02*
X561370D01*
G01X561460Y16080D02*
X560820D01*
G01X560910Y15990D02*
X561560D01*
G01X561650Y15880D02*
X561010D01*
G01X561100Y15790D02*
X561740D01*
G01X561930Y15580D02*
X561290D01*
G01X561470Y15380D02*
X562080D01*
G01X562070Y15440D02*
X558260Y19530D01*
G01X561740Y15100D02*
X561760Y15080D01*
G01X558610Y18470D02*
X561740Y15100D01*
G01X561660Y15190D02*
X561880D01*
G01X544800Y15420D02*
X550220Y21030D01*
G01X544770Y15390D02*
X544800Y15420D01*
G01X544780Y15370D02*
X544770Y15390D01*
G01X545090Y15100D02*
X544780Y15370D01*
G01X545120Y15090D02*
X545090Y15100D01*
G01X545140D02*
X545120Y15090D01*
G01X550260Y20400D02*
X545140Y15100D01*
G01X545220Y15190D02*
X544990D01*
G01X544870Y15290D02*
X545320D01*
G01X545420Y15380D02*
X544770D01*
G01X544860Y15490D02*
X545520D01*
G01X545610Y15580D02*
X544960D01*
G01X545050Y15690D02*
X545710D01*
G01X545800Y15790D02*
X545150D01*
G01X545240Y15880D02*
X545900D01*
G01X546000Y15990D02*
X545340D01*
G01X545440Y16080D02*
X546090D01*
G01X546190Y16190D02*
X545540D01*
G01X545630Y16290D02*
X546290D01*
G01X546380Y16380D02*
X545730D01*
G01X545830Y16490D02*
X546480D01*
G01X546580Y16580D02*
X545920D01*
G01X546020Y16690D02*
X546670D01*
G01X561840Y15690D02*
X561190D01*
G01X561380Y15490D02*
X562020D01*
G01X561790Y15100D02*
X561760Y15080D01*
G01X562080Y15390D02*
X561790Y15100D01*
G01X562090Y15410D02*
X562080Y15390D01*
G01Y15420D02*
X562090Y15410D01*
G01X562070Y15440D02*
X562080Y15420D01*
G01X561560Y15290D02*
X561980D01*
G01X544470Y34300D02*
X544500Y34320D01*
G01X544470Y33760D02*
Y34300D01*
G01X544480Y33740D02*
X544470Y33760D01*
G01X544530Y33630D02*
X544480Y33740D01*
G01X544540Y33620D02*
X544530Y33630D01*
G01X549720Y28030D02*
X544540Y33620D01*
G01X544470Y34290D02*
X544530D01*
G01X544470Y34190D02*
X544620D01*
G01X544710Y34080D02*
X544470D01*
G01Y33990D02*
X544810D01*
G01X544900Y33880D02*
X544470D01*
G01Y33790D02*
X544990D01*
G01X545090Y33690D02*
X544500D01*
G01X544570Y33580D02*
X545180D01*
G01X545270Y33490D02*
X544660D01*
G01X544750Y33380D02*
X545360D01*
G01X545460Y33290D02*
X544850D01*
G01X544940Y33190D02*
X545550D01*
G01X545640Y33080D02*
X545030D01*
G01X545120Y32990D02*
X545740D01*
G01X545830Y32880D02*
X545220D01*
G01X545310Y32790D02*
X545920D01*
G01X546020Y32690D02*
X545400D01*
G01X545500Y32580D02*
X546110D01*
G01X546200Y32490D02*
X545590D01*
G01X545680Y32380D02*
X546300D01*
G01X546390Y32290D02*
X545780D01*
G01X545870Y32190D02*
X546480D01*
G01X546580Y32080D02*
X545960D01*
G01X546050Y31990D02*
X546670D01*
G01X546760Y31880D02*
X546150D01*
G01X546240Y31790D02*
X546850D01*
G01X546950Y31690D02*
X546330D01*
G01X546430Y31580D02*
X547040D01*
G01X547130Y31490D02*
X546520D01*
G01X546610Y31380D02*
X547220D01*
G01X547320Y31290D02*
X546710D01*
G01X546800Y31190D02*
X547410D01*
G01X547500Y31080D02*
X546890D01*
G01X546980Y30990D02*
X547600D01*
G01X547690Y30880D02*
X547080D01*
G01X547170Y30790D02*
X547780D01*
G01X547880Y30690D02*
X547260D01*
G01X547350Y30580D02*
X547970D01*
G01X548060Y30490D02*
X547450D01*
G01X547540Y30380D02*
X548160D01*
G01X548250Y30290D02*
X547630D01*
G01X547720Y30190D02*
X548340D01*
G01X548440Y30080D02*
X547820D01*
G01X547910Y29990D02*
X548530D01*
G01X548620Y29880D02*
X548000D01*
G01X548090Y29790D02*
X548720D01*
G01X548810Y29690D02*
X548190D01*
G01X548280Y29580D02*
X548900D01*
G01X548990Y29490D02*
X548370D01*
G01X548470Y29380D02*
X549090D01*
G01X549180Y29290D02*
X548560D01*
G01X548650Y29190D02*
X549270D01*
G01X549370Y29080D02*
X548750D01*
G01X548930Y28880D02*
X550170D01*
G01X550180Y28690D02*
X549120D01*
G01X548870Y30980D02*
X549380D01*
G01X548830Y30940D02*
X548870Y30980D01*
G01X548830Y30480D02*
Y30940D01*
G01X548870Y30440D02*
X548830Y30480D01*
G01Y30880D02*
X559080D01*
G01X559010Y30690D02*
X548830D01*
G01Y30490D02*
X558850D01*
G01X551480Y31790D02*
X550050D01*
G01X549470Y31050D02*
X549380Y30980D01*
G01X549490Y31100D02*
X549470Y31050D01*
G01X549490Y31110D02*
Y31100D01*
G01X549610Y31360D02*
X549490Y31110D01*
G01X549630Y31370D02*
X549610Y31360D01*
G01X550060Y31790D02*
X549630Y31370D01*
G01X549390Y30990D02*
X550120D01*
G01X550230Y31320D02*
X550340Y31390D01*
G01X550060Y31150D02*
X550230Y31320D01*
G01X550040Y31040D02*
X550060Y31150D01*
G01X550130Y30980D02*
X550040Y31040D01*
G01X550200Y31290D02*
X549580D01*
G01X549530Y31190D02*
X550100D01*
G01X550050Y31080D02*
X549480D01*
G01X549740Y31490D02*
X551420D01*
G01Y31690D02*
X549950D01*
G01X550300Y28090D02*
X553530Y24610D01*
G01X550290Y28090D02*
X550300D01*
G01X550250Y28140D02*
X550290Y28090D01*
G01X550220Y28200D02*
X550250Y28140D01*
G01X550040Y30330D02*
X550220Y28200D01*
G01X550140Y30440D02*
X550040Y30330D01*
G01X550560Y24290D02*
X550090D01*
G01X550080Y24490D02*
X550540D01*
G01X550520Y24690D02*
X550060D01*
G01X550040Y24880D02*
X550510D01*
G01X550490Y25080D02*
X550020D01*
G01X550000Y25290D02*
X550470D01*
G01X550460Y25490D02*
X549990D01*
G01X549970Y25690D02*
X550440D01*
G01X550420Y25880D02*
X549950D01*
G01X549940Y26080D02*
X550410D01*
G01X550390Y26290D02*
X549920D01*
G01X549900Y26490D02*
X550370D01*
G01X550350Y26690D02*
X549890D01*
G01X549870Y26880D02*
X550340D01*
G01X550320Y27080D02*
X549850D01*
G01X549840Y27190D02*
X550350D01*
G01X550850Y27490D02*
X549820D01*
G01X549800Y27690D02*
X550670D01*
G01X549740Y28000D02*
X549720Y28030D01*
G01X549780Y27900D02*
X549740Y28000D01*
G01X549780Y27890D02*
Y27900D01*
G01Y27880D02*
Y27890D01*
G01X550480Y27880D02*
X549780D01*
G01X549680Y28080D02*
X550300D01*
G01X550230Y28190D02*
X549580D01*
G01X549490Y28290D02*
X550220D01*
G01X550210Y28380D02*
X549400D01*
G01X549300Y28490D02*
X550200D01*
G01X550190Y28580D02*
X549210D01*
G01X549020Y28790D02*
X550170D01*
G01X550160Y28990D02*
X549680D01*
G01X549470Y30440D02*
X548870D01*
G01X549570Y30350D02*
X549470Y30440D01*
G01X549690Y29000D02*
X549570Y30350D01*
G01X549530Y30380D02*
X550090D01*
G01X550040Y30290D02*
X549580D01*
G01X549590Y30190D02*
X550060D01*
G01Y30080D02*
X549590D01*
G01X549600Y29990D02*
X550070D01*
G01X550080Y29880D02*
X549610D01*
G01X549620Y29790D02*
X550090D01*
G01X550100Y29690D02*
X549630D01*
G01X549640Y29580D02*
X550110D01*
G01Y29490D02*
X549650D01*
G01Y29380D02*
X550120D01*
G01X550130Y29290D02*
X549670D01*
G01Y29190D02*
X550140D01*
G01X550150Y29080D02*
X549680D01*
G01X549520Y28930D02*
X544500Y34320D01*
G01X549630Y28900D02*
X549520Y28930D01*
G01X549690Y29000D02*
X549630Y28900D01*
G01X548840Y28990D02*
X549460D01*
G01X550110Y24080D02*
X550580D01*
G01X550570Y24190D02*
X550100D01*
G01X550080Y24380D02*
X550550D01*
G01X550540Y24580D02*
X550070D01*
G01X550050Y24790D02*
X550520D01*
G01X550500Y24990D02*
X550030D01*
G01X550020Y25190D02*
X550480D01*
G01X550460Y25380D02*
X550000D01*
G01X549980Y25580D02*
X550450D01*
G01X550430Y25790D02*
X549960D01*
G01X549950Y25990D02*
X550410D01*
G01X550400Y26190D02*
X549930D01*
G01X549910Y26380D02*
X550380D01*
G01X550360Y26580D02*
X549890D01*
G01X549880Y26790D02*
X550340D01*
G01X550330Y26990D02*
X549860D01*
G01X550490Y27210D02*
X553220Y24270D01*
G01X550370Y27230D02*
X550490Y27210D01*
G01X550320Y27130D02*
X550370Y27230D01*
G01X550510Y27190D02*
X551130D01*
G01X551320Y26990D02*
X550700D01*
G01X550880Y26790D02*
X551500D01*
G01X550760Y27580D02*
X549810D01*
G01X549790Y27790D02*
X550580D01*
G01X550390Y27990D02*
X549750D01*
G01X550450Y31400D02*
X550340Y31390D01*
G01X550500Y31310D02*
X550450Y31400D01*
G01X550500Y31080D02*
Y31310D01*
G01X550400Y30980D02*
X550500Y31080D01*
G01X550130Y30980D02*
X550400D01*
G01X550330Y31380D02*
X549640D01*
G01X550510Y32370D02*
X550540Y32390D01*
G01X550500Y32340D02*
X550510Y32370D01*
G01X550500Y32140D02*
Y32340D01*
G01X550490Y32100D02*
X550500Y32140D01*
G01X550470Y32050D02*
X550490Y32100D01*
G01X550420Y31990D02*
X550470Y32050D01*
G01X550330Y31950D02*
X550420Y31990D01*
G01X550060Y31790D02*
X550330Y31950D01*
G01X550540Y32380D02*
X551370D01*
G01X550500Y32190D02*
X553390D01*
G01X553380Y31990D02*
X550400D01*
G01X550450Y31380D02*
X551420D01*
G01Y31190D02*
X550500D01*
G01X550410Y30990D02*
X551520D01*
G01X552740Y24790D02*
X553370D01*
G01X553180Y24990D02*
X552560D01*
G01X552370Y25190D02*
X552990D01*
G01X552810Y25380D02*
X552180D01*
G01X552090Y25490D02*
X552710D01*
G01X552620Y25580D02*
X552000D01*
G01X551910Y25690D02*
X552530D01*
G01X552430Y25790D02*
X551810D01*
G01X551720Y25880D02*
X552340D01*
G01X552250Y25990D02*
X551630D01*
G01X551530Y26080D02*
X552160D01*
G01X552060Y26190D02*
X551440D01*
G01X551350Y26290D02*
X551970D01*
G01X551880Y26380D02*
X551250D01*
G01X551160Y26490D02*
X551780D01*
G01X551690Y26580D02*
X551070D01*
G01X550980Y26690D02*
X551600D01*
G01X551410Y26880D02*
X550790D01*
G01X550600Y27080D02*
X551220D01*
G01X551040Y27290D02*
X549840D01*
G01X549830Y27380D02*
X550950D01*
G01X552800Y26660D02*
X552840Y26620D01*
G01X551420Y31080D02*
X550500D01*
G01X551520Y30980D02*
X551420Y31080D01*
G01X550500Y31290D02*
X551420D01*
G01X552750Y31990D02*
X552860Y31880D01*
G01X552480Y31960D02*
X552750Y31990D01*
G01X552200Y31930D02*
X552480Y31960D01*
G01X552080Y31920D02*
X552200Y31930D01*
G01X551980Y31900D02*
X552080Y31920D01*
G01X551730Y31860D02*
X551980Y31900D01*
G01X551720Y31860D02*
X551730D01*
G01X551630Y31840D02*
X551720Y31860D01*
G01X551620Y31840D02*
X551630D01*
G01X551500Y31820D02*
X551620Y31840D01*
G01X551420Y31720D02*
X551500Y31820D01*
G01X551420Y31080D02*
Y31720D01*
G01X551360Y32390D02*
X550540D01*
G01X551380Y32380D02*
X551360Y32390D01*
G01X551410Y32370D02*
X551380Y32380D01*
G01X551440Y32350D02*
X551410Y32370D01*
G01X551520Y32330D02*
X551440Y32350D01*
G01X551540Y32340D02*
X551520Y32330D01*
G01X551780Y32380D02*
X551540Y32340D01*
G01X552280Y32450D02*
X551780Y32380D01*
G01X552400Y32460D02*
X552280Y32450D01*
G01X552460Y32460D02*
X552400D01*
G01X552620Y32480D02*
X552460Y32460D01*
G01X552760Y32490D02*
X552620Y32480D01*
G01X550220Y31880D02*
X551870D01*
G01X551420Y31580D02*
X549850D01*
G01X551520Y30980D02*
X557360D01*
G01X555430Y32490D02*
X552740D01*
G01X552760D02*
X552860Y32590D01*
G01X553980Y24120D02*
Y24260D01*
G01X554000Y24290D02*
X553210D01*
G01X553220Y24270D02*
Y24130D01*
G01X554020Y24080D02*
X553170D01*
G01X553220Y24190D02*
X553980D01*
G01X554100Y24380D02*
X553110D01*
G01X553020Y24490D02*
X554200D01*
G01X554300Y24580D02*
X552930D01*
G01X552840Y24690D02*
X553460D01*
G01X553670Y24610D02*
X555100Y26080D01*
G01X553530Y24610D02*
X553670D01*
G01X555000Y25990D02*
X555640D01*
G01X555450Y25790D02*
X554810D01*
G01X554720Y25690D02*
X555350D01*
G01X555260Y25580D02*
X554620D01*
G01X554520Y25490D02*
X555160D01*
G01X555070Y25380D02*
X554430D01*
G01X554330Y25290D02*
X554970D01*
G01X554870Y25190D02*
X554230D01*
G01X554140Y25080D02*
X554780D01*
G01X554680Y24990D02*
X554040D01*
G01X553950Y24880D02*
X554580D01*
G01X554490Y24790D02*
X553850D01*
G01X553750Y24690D02*
X554390D01*
G01X553270Y24880D02*
X552650D01*
G01X552460Y25080D02*
X553090D01*
G01X552900Y25290D02*
X552280D01*
G01X552890Y26620D02*
X555380D01*
G01X552840D02*
X552890D01*
G01X555390Y26380D02*
X556030D01*
G01X555840Y26190D02*
X555200D01*
G01X556320Y26690D02*
X552800D01*
G01X552840Y27650D02*
X552890D01*
G01X552800Y27610D02*
X552840Y27650D01*
G01X552800Y26660D02*
Y27610D01*
G01Y27490D02*
X556060D01*
G01X556090Y27290D02*
X552800D01*
G01Y27080D02*
X556710D01*
G01X556510Y26880D02*
X552800D01*
G01X552860Y31540D02*
Y31880D01*
G01X552900Y31490D02*
X552860Y31540D01*
G01X552850Y31880D02*
X555480D01*
G01X555350Y31490D02*
X552900D01*
G01X555400Y31540D02*
X555350Y31490D01*
G01X555400Y31820D02*
Y31540D01*
G01X552860Y31580D02*
X555400D01*
G01Y31690D02*
X552860D01*
G01Y31790D02*
X555400D01*
G01X554950Y32100D02*
Y32060D01*
G01X554850Y32200D02*
X554950Y32100D01*
G01X553410Y32200D02*
X554850D01*
G01X553310Y32100D02*
X553410Y32200D01*
G01X553310Y32060D02*
Y32100D01*
G01X553410Y31950D02*
X553310Y32060D01*
G01X554850Y31950D02*
X553410D01*
G01X554950Y32060D02*
X554850Y31950D01*
G01X554950Y32080D02*
X556920D01*
G01X556630Y32190D02*
X554860D01*
G01X552860Y32620D02*
Y32590D01*
G01X552900Y32660D02*
X552860Y32620D01*
G01X555350Y32660D02*
X552900D01*
G01X555400Y32620D02*
X555350Y32660D01*
G01X555400Y32520D02*
Y32620D01*
G01X552850Y32580D02*
X555400D01*
G01X553310Y32080D02*
X550480D01*
G01X550500Y32290D02*
X556260D01*
G01X555480Y32420D02*
X555400Y32520D01*
G01X555530Y32420D02*
X555480D01*
G01X556090Y32330D02*
X555530Y32420D01*
G01X556270Y32290D02*
X556090Y32330D01*
G01X555710Y32380D02*
X551840D01*
G01X555910Y31850D02*
X556320Y31760D01*
G01X555620Y31900D02*
X555910Y31850D01*
G01X555590Y31900D02*
X555620D01*
G01X555510Y31920D02*
X555590Y31900D01*
G01X555400Y31820D02*
X555510Y31920D01*
G01X555700Y31880D02*
X557290D01*
G01X556010Y27650D02*
X552890D01*
G01X552800Y27580D02*
X556060D01*
G01X556050Y27610D02*
X556010Y27650D01*
G01X556230Y27260D02*
X556430Y27460D01*
G01X556120Y27230D02*
X556230Y27260D01*
G01X556060Y27330D02*
X556120Y27230D01*
G01X556060Y27510D02*
Y27330D01*
G01Y27520D02*
Y27510D01*
G01X556050Y27610D02*
X556060Y27520D01*
G01X556260Y27290D02*
X556900D01*
G01X556060Y27380D02*
X552800D01*
G01X554910Y25880D02*
X555550D01*
G01X555470Y26560D02*
X555380Y26620D01*
G01X555450Y26450D02*
X555470Y26560D01*
G01X555100Y26080D02*
X555450Y26450D01*
G01X555740Y26080D02*
X555100D01*
G01X555430Y26580D02*
X556220D01*
G01X556130Y26490D02*
X555460D01*
G01X555300Y26290D02*
X555930D01*
G01X556450Y27490D02*
X556430Y27460D01*
G01X557090Y27490D02*
X556450D01*
G01D02*
X557260Y28330D01*
G01X556840Y27880D02*
X559100D01*
G01Y27690D02*
X556650D01*
G01X556350Y27380D02*
X556990D01*
G01X556800Y27190D02*
X552800D01*
G01Y26990D02*
X556610D01*
G01X556410Y26790D02*
X552800D01*
G01X556600Y31680D02*
X556320Y31760D01*
G01X556610Y31670D02*
X556600Y31680D01*
G01X556720Y31640D02*
X556610Y31670D01*
G01X556720Y31630D02*
Y31640D01*
G01X556830Y31590D02*
X556720Y31630D01*
G01X556840Y31580D02*
X556830Y31590D01*
G01X557700Y31580D02*
X556840D01*
G01X556560Y31690D02*
X557590D01*
G01X556390Y32250D02*
X556270Y32290D01*
G01X556500Y32230D02*
X556390Y32250D01*
G01X556740Y32150D02*
X556500Y32230D01*
G01X556850Y32110D02*
X556740Y32150D01*
G01X556910Y32090D02*
X556850Y32110D01*
G01X556200Y31790D02*
X557450D01*
G01X557130Y31990D02*
X554880D01*
G01X557450Y31030D02*
X557360Y30980D01*
G01X557440Y31130D02*
X557450Y31030D01*
G01X557370Y31240D02*
X557440Y31130D01*
G01X557350Y31260D02*
X557370Y31240D01*
G01X557050Y31480D02*
X557350Y31260D01*
G01X557040Y31490D02*
X557050Y31480D01*
G01X557030Y31490D02*
X557040D01*
G01X556840Y31580D02*
X557030Y31490D01*
G01X557370Y30990D02*
X559090D01*
G01X559070Y31190D02*
X557410D01*
G01X557180Y31380D02*
X558990D01*
G01X559100Y29380D02*
X557320D01*
G01X557290Y28360D02*
X557260Y28330D01*
G01X557320Y28420D02*
X557290Y28360D01*
G01X557320Y29440D02*
Y28420D01*
G01X557220Y28290D02*
X557890D01*
G01X558060Y28490D02*
X557320D01*
G01Y28690D02*
X558250D01*
G01X558440Y28880D02*
X557320D01*
G01Y28990D02*
X559100D01*
G01Y29190D02*
X557320D01*
G01X557430Y29520D02*
X557530Y29620D01*
G01X557360Y29520D02*
X557430D01*
G01X557320Y29480D02*
X557360Y29520D01*
G01X557320Y29440D02*
Y29480D01*
G01X557030Y28080D02*
X559100D01*
G01X557820Y27380D02*
X557350D01*
G01X557190Y27590D02*
X553980Y24260D01*
G01X557300Y27610D02*
X557190Y27590D01*
G01X557360Y27510D02*
X557300Y27610D01*
G01X557080Y24080D02*
X557550D01*
G01X557560Y24190D02*
X557090D01*
G01X557110Y24380D02*
X557580D01*
G01X557590Y24580D02*
X557130D01*
G01X557140Y24790D02*
X557610D01*
G01X557620Y24990D02*
X557160D01*
G01X557170Y25190D02*
X557640D01*
G01X557660Y25380D02*
X557190D01*
G01X557210Y25580D02*
X557670D01*
G01X557690Y25790D02*
X557220D01*
G01X557240Y25990D02*
X557710D01*
G01X557720Y26190D02*
X557260D01*
G01X557270Y26380D02*
X557740D01*
G01X557750Y26580D02*
X557290D01*
G01X557300Y26790D02*
X557770D01*
G01X557790Y26990D02*
X557320D01*
G01X557340Y27190D02*
X557800D01*
G01X557190Y27580D02*
X556550D01*
G01X557060Y32030D02*
X556910Y32090D01*
G01X557070Y32020D02*
X557060Y32030D01*
G01X558320Y31740D02*
X558380Y31750D01*
G01X558310Y31740D02*
X558320D01*
G01X558200Y31710D02*
X558310Y31740D01*
G01X558190Y31710D02*
X558200D01*
G01X558060Y31660D02*
X558190Y31710D01*
G01X558060Y31650D02*
Y31660D01*
G01X558000Y31620D02*
X558060Y31650D01*
G01X557980Y31600D02*
X558000Y31620D01*
G01X557920Y31550D02*
X557980Y31600D01*
G01X557900Y31530D02*
X557920Y31550D01*
G01X557760Y31530D02*
X557900D01*
G01X557580Y31700D02*
X557760Y31530D01*
G01X557570Y31710D02*
X557580Y31700D01*
G01X557070Y32020D02*
X557570Y31710D01*
G01X558130Y31690D02*
X558650D01*
G01X558700Y30380D02*
X557540D01*
G01X557590Y30330D02*
X557530Y29620D01*
G01X557500Y29580D02*
X558050D01*
G01X558340Y30310D02*
X558370Y30300D01*
G01X558260Y30320D02*
X558340Y30310D01*
G01X558190Y30340D02*
X558260Y30320D01*
G01X558180Y30340D02*
X558190D01*
G01X558050Y30250D02*
X558180Y30340D01*
G01X558000Y29640D02*
X558050Y30250D01*
G01X558100Y29530D02*
X558000Y29640D01*
G01X558100Y30290D02*
X557590D01*
G01X557490Y30440D02*
X550140D01*
G01X557590Y30330D02*
X557490Y30440D01*
G01X557130Y28190D02*
X557950D01*
G01X557920Y28340D02*
X558470Y28920D01*
G01X557890Y28290D02*
X557920Y28340D01*
G01X557890Y28250D02*
Y28290D01*
G01X557990Y28140D02*
X557890Y28250D01*
G01X558350Y28790D02*
X557320D01*
G01Y28580D02*
X558150D01*
G01X557960Y28380D02*
X557300D01*
G01X557320Y27580D02*
X557850D01*
G01X557570Y24290D02*
X557100D01*
G01X557110Y24490D02*
X557580D01*
G01X557600Y24690D02*
X557130D01*
G01X557150Y24880D02*
X557610D01*
G01X557630Y25080D02*
X557170D01*
G01X557180Y25290D02*
X557650D01*
G01X557670Y25490D02*
X557200D01*
G01X557210Y25690D02*
X557680D01*
G01X557700Y25880D02*
X557230D01*
G01X557250Y26080D02*
X557710D01*
G01X557730Y26290D02*
X557260D01*
G01X557280Y26490D02*
X557740D01*
G01X557760Y26690D02*
X557300D01*
G01X557310Y26880D02*
X557780D01*
G01X557800Y27080D02*
X557330D01*
G01X557340Y27290D02*
X557810D01*
G01X557830Y27490D02*
X557360D01*
G01X557840Y27570D02*
X557930Y27660D01*
G01X558260Y29520D02*
X558380D01*
G01X558100Y29530D02*
X558260Y29520D01*
G01X558010Y29690D02*
X557540D01*
G01X557550Y29790D02*
X558020D01*
G01Y29880D02*
X557560D01*
G01Y29990D02*
X558030D01*
G01X558040Y30080D02*
X557570D01*
G01X557580Y30190D02*
X558050D01*
G01X558450Y31750D02*
X558380D01*
G01X558460Y31740D02*
X558450Y31750D01*
G01X558720Y31670D02*
X558460Y31740D01*
G01X558730Y31660D02*
X558720Y31670D01*
G01X558930Y31490D02*
X558730Y31660D01*
G01X558940Y31480D02*
X558930Y31490D01*
G01X559060Y31250D02*
X558940Y31480D01*
G01X559070Y31230D02*
X559060Y31250D01*
G01X559090Y30950D02*
X559070Y31230D01*
G01X559090Y30940D02*
Y30950D01*
G01X559010Y30680D02*
X559090Y30940D01*
G01X559000Y30670D02*
X559010Y30680D01*
G01X558840Y30470D02*
X559000Y30670D01*
G01X558830Y30450D02*
X558840Y30470D01*
G01X558600Y30330D02*
X558830Y30450D01*
G01X558580Y30330D02*
X558600D01*
G01X558460Y30310D02*
X558580Y30330D01*
G01X558450Y30310D02*
X558460D01*
G01X558390Y30300D02*
X558450Y30310D01*
G01X558370Y30300D02*
X558390D01*
G01X557960Y31580D02*
X558820D01*
G01X558930Y31490D02*
X557040D01*
G01X557320Y31290D02*
X559040D01*
G01X559080Y31080D02*
X557450D01*
G01X558940Y30580D02*
X548830D01*
G01Y30790D02*
X559040D01*
G01X559350Y30490D02*
X559980D01*
G01X560080Y30580D02*
X559450D01*
G01X559540Y30690D02*
X560180D01*
G01X560270Y30790D02*
X559640D01*
G01X559740Y30880D02*
X560370D01*
G01X560460Y30990D02*
X559840D01*
G01X559930Y31080D02*
X560560D01*
G01X560660Y31190D02*
X560030D01*
G01X560130Y31290D02*
X560760D01*
G01X560950Y31490D02*
X560320D01*
G01X560510Y31690D02*
X561140D01*
G01X559890Y30380D02*
X559260D01*
G01X559160Y30290D02*
X559790D01*
G01X559690Y30190D02*
X559060D01*
G01X558960Y30080D02*
X559600D01*
G01X559500Y29990D02*
X558870D01*
G01X558770Y29880D02*
X559410D01*
G01X559310Y29790D02*
X558680D01*
G01X558580Y29690D02*
X559210D01*
G01X559060Y27660D02*
X557930D01*
G01X559100Y27680D02*
X559060Y27660D01*
G01X559100Y27690D02*
Y27680D01*
G01Y29510D02*
Y27690D01*
G01Y29520D02*
Y29510D01*
G01X559130Y29600D02*
X559100Y29520D01*
G01X558580Y28940D02*
X558470Y28920D01*
G01X558640Y28840D02*
X558580Y28940D01*
G01X558640Y28240D02*
Y28840D01*
G01X558540Y28140D02*
X558640Y28240D01*
G01X557990Y28140D02*
X558540D01*
G01X558610Y28880D02*
X559100D01*
G01Y28790D02*
X558640D01*
G01Y28690D02*
X559100D01*
G01Y28580D02*
X558640D01*
G01Y28490D02*
X559100D01*
G01Y28380D02*
X558640D01*
G01Y28290D02*
X559100D01*
G01Y28190D02*
X558590D01*
G01X559100Y27990D02*
X556930D01*
G01X556740Y27790D02*
X559100D01*
G01Y29080D02*
X557320D01*
G01Y29290D02*
X559100D01*
G01Y29490D02*
X557320D01*
G01X558380Y29520D02*
X558450Y29550D01*
G01X558480Y29580D02*
X559120D01*
G01X558450Y29550D02*
X563030Y34290D01*
G01X563060Y33680D02*
X559130Y29600D01*
G01X560220Y31380D02*
X560850D01*
G01X561040Y31580D02*
X560410D01*
G01X560610Y31790D02*
X561240D01*
G01X561340Y31880D02*
X560710D01*
G01X560800Y31990D02*
X561430D01*
G01X561530Y32080D02*
X560900D01*
G01X561000Y32190D02*
X561620D01*
G01X561720Y32290D02*
X561090D01*
G01X561280Y32490D02*
X561910D01*
G01X562110Y32690D02*
X561480D01*
G01X561670Y32880D02*
X562300D01*
G01X562200Y32790D02*
X561580D01*
G01X561770Y32990D02*
X562390D01*
G01X562490Y33080D02*
X561860D01*
G01X561960Y33190D02*
X562590D01*
G01X562690Y33290D02*
X562060D01*
G01X562150Y33380D02*
X562780D01*
G01X562880Y33490D02*
X562250D01*
G01X562350Y33580D02*
X562970D01*
G01X563080Y33790D02*
X562540D01*
G01X563070Y33710D02*
X563080Y33790D01*
G01X563060Y33680D02*
X563070Y33710D01*
G01X562450Y33690D02*
X563060D01*
G01X563080Y34280D02*
X563030Y34290D01*
G01X563080Y33790D02*
Y34280D01*
G01X563020Y34290D02*
X563060D01*
G01X563080Y34190D02*
X562930D01*
G01X562830Y34080D02*
X563080D01*
G01Y33990D02*
X562730D01*
G01X562640Y33880D02*
X563080D01*
G01X562010Y32580D02*
X561380D01*
G01X561190Y32380D02*
X561820D01*
G54D14*
G01X981Y-184981D02*
X1855Y-184106D01*
X2510Y-182648D01*
X2947Y-180605D01*
X2510Y-178856D01*
X1637Y-177689D01*
X108Y-176814D01*
X-5787D01*
Y-194314D01*
X1418D01*
X2947Y-193148D01*
X3820Y-191397D01*
X4257Y-189356D01*
X3820Y-187314D01*
X2510Y-185564D01*
X981Y-184981D01*
X-5787D01*
G01X13678Y-194314D02*
Y-182648D01*
G01Y-184981D02*
X14770Y-183814D01*
X15862Y-182939D01*
X17390Y-182648D01*
X18481Y-182939D01*
X19792Y-183814D01*
G01X29650Y-199564D02*
X30960Y-200147D01*
X32707Y-199564D01*
X33798Y-198398D01*
X34672Y-196939D01*
X35981Y-192273D01*
X38820Y-182648D01*
G01X31833D02*
X35981Y-192273D01*
G01X55228Y-184106D02*
X53700Y-182939D01*
X52390Y-182648D01*
X50643Y-183231D01*
X49333Y-184397D01*
X48460Y-186439D01*
X48241Y-188481D01*
X48460Y-190523D01*
X49333Y-192273D01*
X50643Y-193731D01*
X52390Y-194314D01*
X53918Y-193731D01*
X55228Y-192564D01*
G01X65960Y-186439D02*
X72947D01*
X72292Y-184397D01*
X71200Y-183231D01*
X69672Y-182648D01*
X68143Y-182939D01*
X66833Y-183814D01*
X65960Y-185856D01*
X65523Y-187606D01*
Y-189356D01*
X65960Y-191106D01*
X67052Y-192856D01*
X68362Y-194022D01*
X69890Y-194314D01*
X71418Y-193731D01*
X72947Y-191981D01*
G01X109038Y-178273D02*
X107728Y-177397D01*
X106200Y-176814D01*
X104453D01*
X102488Y-177689D01*
X100960Y-179147D01*
X99868Y-180898D01*
X98995Y-183814D01*
X98776Y-186439D01*
X99213Y-189064D01*
X99868Y-190814D01*
X101178Y-192564D01*
X102707Y-193731D01*
X104235Y-194314D01*
X105763D01*
X107292Y-193731D01*
X108602Y-192856D01*
X109694Y-191690D01*
G01X125665Y-194314D02*
Y-182648D01*
G01Y-184689D02*
X124792Y-183523D01*
X123481Y-182939D01*
X121953Y-182648D01*
X120425Y-183231D01*
X119115Y-184397D01*
X118241Y-186147D01*
X117805Y-188481D01*
X118241Y-190814D01*
X119115Y-192564D01*
X120425Y-193731D01*
X121953Y-194314D01*
X123481Y-194022D01*
X124792Y-193148D01*
X125665Y-191981D01*
G01X135523Y-194314D02*
Y-182648D01*
G01Y-185564D02*
X136397Y-184106D01*
X137707Y-182939D01*
X139453Y-182648D01*
X140981Y-182939D01*
X142292Y-184106D01*
X142947Y-186147D01*
Y-194314D01*
G01X152150Y-199564D02*
X153460Y-200147D01*
X155207Y-199564D01*
X156298Y-198398D01*
X157172Y-196939D01*
X158481Y-192273D01*
X161320Y-182648D01*
G01X154333D02*
X158481Y-192273D01*
G01X174235Y-194314D02*
X172925Y-194022D01*
X171615Y-192856D01*
X170741Y-190814D01*
X170305Y-188481D01*
X170741Y-186147D01*
X171615Y-184106D01*
X172925Y-182939D01*
X174235Y-182648D01*
X175545Y-182939D01*
X176855Y-184106D01*
X177728Y-186147D01*
X177947Y-188481D01*
X177728Y-190814D01*
X176855Y-192856D01*
X175545Y-194022D01*
X174235Y-194314D01*
G01X188023D02*
Y-182648D01*
G01Y-185564D02*
X188897Y-184106D01*
X190207Y-182939D01*
X191953Y-182648D01*
X193481Y-182939D01*
X194792Y-184106D01*
X195447Y-186147D01*
Y-194314D01*
G01X222368Y-176814D02*
Y-194314D01*
X231102D01*
G01X248602D02*
X239868D01*
Y-176814D01*
X248602D01*
G01X245108Y-185272D02*
X239868D01*
G01X256932Y-194314D02*
Y-176814D01*
X261298D01*
X263045Y-177689D01*
X264355Y-178856D01*
X265447Y-180605D01*
X266320Y-182648D01*
X266538Y-185564D01*
X266320Y-188481D01*
X265447Y-190523D01*
X264355Y-192273D01*
X263045Y-193439D01*
X261298Y-194314D01*
X256932D01*
G01X298481Y-184981D02*
X299355Y-184106D01*
X300010Y-182648D01*
X300447Y-180605D01*
X300010Y-178856D01*
X299137Y-177689D01*
X297608Y-176814D01*
X291713D01*
Y-194314D01*
X298918D01*
X300447Y-193148D01*
X301320Y-191397D01*
X301757Y-189356D01*
X301320Y-187314D01*
X300010Y-185564D01*
X298481Y-184981D01*
X291713D01*
G01X314235Y-194314D02*
X312925Y-194022D01*
X311615Y-192856D01*
X310741Y-190814D01*
X310305Y-188481D01*
X310741Y-186147D01*
X311615Y-184106D01*
X312925Y-182939D01*
X314235Y-182648D01*
X315545Y-182939D01*
X316855Y-184106D01*
X317728Y-186147D01*
X317947Y-188481D01*
X317728Y-190814D01*
X316855Y-192856D01*
X315545Y-194022D01*
X314235Y-194314D01*
G01X335665D02*
Y-182648D01*
G01Y-184689D02*
X334792Y-183523D01*
X333481Y-182939D01*
X331953Y-182648D01*
X330425Y-183231D01*
X329115Y-184397D01*
X328241Y-186147D01*
X327805Y-188481D01*
X328241Y-190814D01*
X329115Y-192564D01*
X330425Y-193731D01*
X331953Y-194314D01*
X333481Y-194022D01*
X334792Y-193148D01*
X335665Y-191981D01*
G01X346178Y-194314D02*
Y-182648D01*
G01Y-184981D02*
X347270Y-183814D01*
X348362Y-182939D01*
X349890Y-182648D01*
X350981Y-182939D01*
X352292Y-183814D01*
G01X370665Y-176814D02*
Y-194314D01*
G01Y-191690D02*
X369792Y-193148D01*
X368481Y-194022D01*
X366953Y-194314D01*
X365207Y-193731D01*
X363897Y-192273D01*
X363023Y-190523D01*
X362805Y-188481D01*
X363023Y-186439D01*
X363897Y-184689D01*
X365207Y-183231D01*
X366953Y-182648D01*
X368481Y-182939D01*
X369573Y-183523D01*
X370665Y-184689D01*
G01X142308Y-149314D02*
Y-131814D01*
X147985Y-146397D01*
X153662Y-131814D01*
Y-149314D01*
G01X165485D02*
X164175Y-149022D01*
X162865Y-147856D01*
X161991Y-145814D01*
X161555Y-143481D01*
X161991Y-141147D01*
X162865Y-139106D01*
X164175Y-137939D01*
X165485Y-137648D01*
X166795Y-137939D01*
X168105Y-139106D01*
X168978Y-141147D01*
X169197Y-143481D01*
X168978Y-145814D01*
X168105Y-147856D01*
X166795Y-149022D01*
X165485Y-149314D01*
G01X186915Y-131814D02*
Y-149314D01*
G01Y-146690D02*
X186042Y-148148D01*
X184731Y-149022D01*
X183203Y-149314D01*
X181457Y-148731D01*
X180147Y-147273D01*
X179273Y-145523D01*
X179055Y-143481D01*
X179273Y-141439D01*
X180147Y-139689D01*
X181457Y-138231D01*
X183203Y-137648D01*
X184731Y-137939D01*
X185823Y-138523D01*
X186915Y-139689D01*
G01X197210Y-141439D02*
X204197D01*
X203542Y-139397D01*
X202450Y-138231D01*
X200922Y-137648D01*
X199393Y-137939D01*
X198083Y-138814D01*
X197210Y-140856D01*
X196773Y-142606D01*
Y-144356D01*
X197210Y-146106D01*
X198302Y-147856D01*
X199612Y-149022D01*
X201140Y-149314D01*
X202668Y-148731D01*
X204197Y-146981D01*
G01X217985Y-149314D02*
Y-131814D01*
G01X423785Y-194314D02*
Y-176814D01*
X421165Y-180314D01*
G01Y-194314D02*
X426405D01*
G01X437137Y-187023D02*
X438665Y-184981D01*
X439975Y-183814D01*
X441722Y-183231D01*
X443250Y-183814D01*
X444342Y-184981D01*
X445215Y-186731D01*
X445433Y-188772D01*
X445215Y-190523D01*
X444342Y-192273D01*
X443031Y-193731D01*
X441503Y-194314D01*
X439757Y-193731D01*
X438228Y-191981D01*
X437355Y-189356D01*
X437137Y-186439D01*
X437573Y-182648D01*
X438228Y-180605D01*
X439320Y-178564D01*
X440848Y-177106D01*
X442377Y-176814D01*
X443905Y-177397D01*
X444997Y-178856D01*
G01X453982Y-190814D02*
X455291Y-192856D01*
X457038Y-194022D01*
X459003Y-194314D01*
X460750Y-194022D01*
X462497Y-192564D01*
X463588Y-190814D01*
X463807Y-189064D01*
X463370Y-187023D01*
X461842Y-185564D01*
X460313Y-184981D01*
X458348D01*
G01X460313D02*
X461623Y-184106D01*
X462715Y-182648D01*
X463152Y-180898D01*
X462715Y-179147D01*
X461623Y-177689D01*
X459658Y-176814D01*
X457693Y-177106D01*
X455728Y-178273D01*
G01X478905Y-194314D02*
Y-176814D01*
X470826Y-189356D01*
X481744D01*
G01X493348Y-194314D02*
X493785Y-190523D01*
X494440Y-187314D01*
X495313Y-184397D01*
X496405Y-181189D01*
X498152Y-176814D01*
X489418D01*
G01X410668Y-149314D02*
Y-131814D01*
X415908D01*
X417655Y-132689D01*
X418965Y-134731D01*
X419402Y-137064D01*
X418965Y-139397D01*
X417873Y-141147D01*
X415908Y-142023D01*
X410668D01*
G01X437338Y-133273D02*
X436028Y-132397D01*
X434500Y-131814D01*
X432753D01*
X430788Y-132689D01*
X429260Y-134147D01*
X428168Y-135898D01*
X427295Y-138814D01*
X427076Y-141439D01*
X427513Y-144064D01*
X428168Y-145814D01*
X429478Y-147564D01*
X431007Y-148731D01*
X432535Y-149314D01*
X434063D01*
X435592Y-148731D01*
X436902Y-147856D01*
X437994Y-146690D01*
G01X451781Y-139981D02*
X452655Y-139106D01*
X453310Y-137648D01*
X453747Y-135605D01*
X453310Y-133856D01*
X452437Y-132689D01*
X450908Y-131814D01*
X445013D01*
Y-149314D01*
X452218D01*
X453747Y-148148D01*
X454620Y-146397D01*
X455057Y-144356D01*
X454620Y-142314D01*
X453310Y-140564D01*
X451781Y-139981D01*
X445013D01*
G01X460985Y-155147D02*
X474085D01*
G01X480013Y-149314D02*
Y-131814D01*
X490057Y-149314D01*
Y-131814D01*
G01X502535Y-149314D02*
X500788Y-149022D01*
X499260Y-147856D01*
X497950Y-146106D01*
X497076Y-144064D01*
X496640Y-141731D01*
Y-139397D01*
X497076Y-137064D01*
X497950Y-135022D01*
X499260Y-133273D01*
X500788Y-132106D01*
X502535Y-131814D01*
X504281Y-132106D01*
X505810Y-133273D01*
X507120Y-135022D01*
X507994Y-137064D01*
X508430Y-139397D01*
Y-141731D01*
X507994Y-144064D01*
X507120Y-146106D01*
X505810Y-147856D01*
X504281Y-149022D01*
X502535Y-149314D01*
G01X553376Y-131814D02*
X558835Y-149314D01*
X564294Y-131814D01*
G01X580702Y-149314D02*
X571968D01*
Y-131814D01*
X580702D01*
G01X577208Y-140272D02*
X571968D01*
G01X589468Y-149314D02*
Y-131814D01*
X594927D01*
X596673Y-132689D01*
X597765Y-133856D01*
X598202Y-136189D01*
X597765Y-138523D01*
X596455Y-139981D01*
X594927Y-140856D01*
X589468D01*
G01X594927D02*
X598202Y-149314D01*
G01X611335Y-149897D02*
X610898Y-149606D01*
Y-149022D01*
X611335Y-148731D01*
X611772Y-149022D01*
Y-149606D01*
X611335Y-149897D01*
G01X585085Y-194314D02*
Y-176814D01*
X582465Y-180314D01*
G01Y-194314D02*
X587705D01*
G01X691285Y-176814D02*
Y-194314D01*
G01X686263Y-176814D02*
X696307D01*
G01X704200Y-191981D02*
X705947Y-193439D01*
X707912Y-194314D01*
X709658D01*
X711405Y-193439D01*
X712715Y-191981D01*
X713370Y-189939D01*
X712933Y-187898D01*
X711842Y-186147D01*
X709877Y-184981D01*
X707257Y-184397D01*
X705728Y-183231D01*
X705073Y-181189D01*
X705510Y-179147D01*
X706602Y-177689D01*
X708130Y-176814D01*
X709658D01*
X711187Y-177397D01*
X712497Y-178856D01*
G01X723665Y-176814D02*
X728905D01*
G01X726285D02*
Y-194314D01*
G01X723665D02*
X728905D01*
G01X739418Y-176814D02*
Y-194314D01*
X748152D01*
G01X756482D02*
Y-176814D01*
G01X764778D02*
X756482Y-187606D01*
G01X766088Y-194314D02*
X760193Y-182648D01*
G01X686918Y-131814D02*
Y-149314D01*
X695652D01*
G01X712715D02*
Y-137648D01*
G01Y-139689D02*
X711842Y-138523D01*
X710531Y-137939D01*
X709003Y-137648D01*
X707475Y-138231D01*
X706165Y-139397D01*
X705291Y-141147D01*
X704855Y-143481D01*
X705291Y-145814D01*
X706165Y-147564D01*
X707475Y-148731D01*
X709003Y-149314D01*
X710531Y-149022D01*
X711842Y-148148D01*
X712715Y-146981D01*
G01X721700Y-154564D02*
X723010Y-155147D01*
X724757Y-154564D01*
X725848Y-153398D01*
X726722Y-151939D01*
X728031Y-147273D01*
X730870Y-137648D01*
G01X723883D02*
X728031Y-147273D01*
G01X740510Y-141439D02*
X747497D01*
X746842Y-139397D01*
X745750Y-138231D01*
X744222Y-137648D01*
X742693Y-137939D01*
X741383Y-138814D01*
X740510Y-140856D01*
X740073Y-142606D01*
Y-144356D01*
X740510Y-146106D01*
X741602Y-147856D01*
X742912Y-149022D01*
X744440Y-149314D01*
X745968Y-148731D01*
X747497Y-146981D01*
G01X758228Y-149314D02*
Y-137648D01*
G01Y-139981D02*
X759320Y-138814D01*
X760412Y-137939D01*
X761940Y-137648D01*
X763031Y-137939D01*
X764342Y-138814D01*
G01X851335Y-194314D02*
X849588Y-194022D01*
X848060Y-192856D01*
X846750Y-191106D01*
X845876Y-189064D01*
X845440Y-186731D01*
Y-184397D01*
X845876Y-182064D01*
X846750Y-180022D01*
X848060Y-178273D01*
X849588Y-177106D01*
X851335Y-176814D01*
X853081Y-177106D01*
X854610Y-178273D01*
X855920Y-180022D01*
X856794Y-182064D01*
X857230Y-184397D01*
Y-186731D01*
X856794Y-189064D01*
X855920Y-191106D01*
X854610Y-192856D01*
X853081Y-194022D01*
X851335Y-194314D01*
G01X853081Y-189647D02*
X855702Y-194314D01*
G01X864032Y-176814D02*
Y-189356D01*
X864905Y-191981D01*
X866652Y-193731D01*
X868835Y-194314D01*
X871018Y-193731D01*
X872765Y-191981D01*
X873638Y-189356D01*
Y-176814D01*
G01X883715D02*
X888955D01*
G01X886335D02*
Y-194314D01*
G01X883715D02*
X888955D01*
G01X898813D02*
Y-176814D01*
X908857Y-194314D01*
Y-176814D01*
G01X926138Y-178273D02*
X924828Y-177397D01*
X923300Y-176814D01*
X921553D01*
X919588Y-177689D01*
X918060Y-179147D01*
X916968Y-180898D01*
X916095Y-183814D01*
X915876Y-186439D01*
X916313Y-189064D01*
X916968Y-190814D01*
X918278Y-192564D01*
X919807Y-193731D01*
X921335Y-194314D01*
X922863D01*
X924392Y-193731D01*
X925702Y-192856D01*
X926794Y-191690D01*
G01X938835Y-194314D02*
Y-186439D01*
X934468Y-176814D01*
G01X943202D02*
X938835Y-186439D01*
G01X829032Y-149314D02*
Y-131814D01*
X833398D01*
X835145Y-132689D01*
X836455Y-133856D01*
X837547Y-135605D01*
X838420Y-137648D01*
X838638Y-140564D01*
X838420Y-143481D01*
X837547Y-145523D01*
X836455Y-147273D01*
X835145Y-148439D01*
X833398Y-149314D01*
X829032D01*
G01X848060Y-141439D02*
X855047D01*
X854392Y-139397D01*
X853300Y-138231D01*
X851772Y-137648D01*
X850243Y-137939D01*
X848933Y-138814D01*
X848060Y-140856D01*
X847623Y-142606D01*
Y-144356D01*
X848060Y-146106D01*
X849152Y-147856D01*
X850462Y-149022D01*
X851990Y-149314D01*
X853518Y-148731D01*
X855047Y-146981D01*
G01X865560Y-147273D02*
X866652Y-148439D01*
X868180Y-149314D01*
X869490D01*
X870800Y-148731D01*
X871673Y-147856D01*
X872110Y-146690D01*
X871892Y-144939D01*
X871018Y-144064D01*
X867088Y-142314D01*
X866215Y-140272D01*
X866652Y-138814D01*
X867525Y-137939D01*
X868835Y-137648D01*
X870145Y-137939D01*
X871455Y-138814D01*
G01X886335Y-137648D02*
Y-149314D01*
G01Y-132981D02*
X885898Y-132689D01*
Y-132106D01*
X886335Y-131814D01*
X886772Y-132106D01*
Y-132689D01*
X886335Y-132981D01*
G01X900778Y-153689D02*
X902307Y-154856D01*
X904053Y-155147D01*
X905581Y-154856D01*
X906892Y-153398D01*
X907765Y-151356D01*
Y-137648D01*
G01Y-139981D02*
X906892Y-138814D01*
X905581Y-137939D01*
X904053Y-137648D01*
X902307Y-138231D01*
X901215Y-139397D01*
X900341Y-141439D01*
X899905Y-143481D01*
X900123Y-145231D01*
X900997Y-147273D01*
X902307Y-148731D01*
X904053Y-149314D01*
X905363Y-149022D01*
X906892Y-147856D01*
X907765Y-146690D01*
G01X917623Y-149314D02*
Y-137648D01*
G01Y-140564D02*
X918497Y-139106D01*
X919807Y-137939D01*
X921553Y-137648D01*
X923081Y-137939D01*
X924392Y-139106D01*
X925047Y-141147D01*
Y-149314D01*
G01X935560Y-141439D02*
X942547D01*
X941892Y-139397D01*
X940800Y-138231D01*
X939272Y-137648D01*
X937743Y-137939D01*
X936433Y-138814D01*
X935560Y-140856D01*
X935123Y-142606D01*
Y-144356D01*
X935560Y-146106D01*
X936652Y-147856D01*
X937962Y-149022D01*
X939490Y-149314D01*
X941018Y-148731D01*
X942547Y-146981D01*
G01X953278Y-149314D02*
Y-137648D01*
G01Y-139981D02*
X954370Y-138814D01*
X955462Y-137939D01*
X956990Y-137648D01*
X958081Y-137939D01*
X959392Y-138814D01*
G01X1000035Y-176814D02*
X998288Y-177397D01*
X996978Y-178856D01*
X996105Y-180605D01*
X995450Y-182939D01*
X995232Y-185564D01*
X995450Y-188189D01*
X996105Y-190523D01*
X996978Y-192273D01*
X998288Y-193731D01*
X1000035Y-194314D01*
X1001781Y-193731D01*
X1003092Y-192273D01*
X1003965Y-190523D01*
X1004620Y-188189D01*
X1004838Y-185564D01*
X1004620Y-182939D01*
X1003965Y-180605D01*
X1003092Y-178856D01*
X1001781Y-177397D01*
X1000035Y-176814D01*
G01X1013387Y-187023D02*
X1014915Y-184981D01*
X1016225Y-183814D01*
X1017972Y-183231D01*
X1019500Y-183814D01*
X1020592Y-184981D01*
X1021465Y-186731D01*
X1021683Y-188772D01*
X1021465Y-190523D01*
X1020592Y-192273D01*
X1019281Y-193731D01*
X1017753Y-194314D01*
X1016007Y-193731D01*
X1014478Y-191981D01*
X1013605Y-189356D01*
X1013387Y-186439D01*
X1013823Y-182648D01*
X1014478Y-180605D01*
X1015570Y-178564D01*
X1017098Y-177106D01*
X1018627Y-176814D01*
X1020155Y-177397D01*
X1021247Y-178856D01*
G01X1031105Y-194897D02*
X1038965Y-176814D01*
G01X1052535D02*
X1050788Y-177397D01*
X1049478Y-178856D01*
X1048605Y-180605D01*
X1047950Y-182939D01*
X1047732Y-185564D01*
X1047950Y-188189D01*
X1048605Y-190523D01*
X1049478Y-192273D01*
X1050788Y-193731D01*
X1052535Y-194314D01*
X1054281Y-193731D01*
X1055592Y-192273D01*
X1056465Y-190523D01*
X1057120Y-188189D01*
X1057338Y-185564D01*
X1057120Y-182939D01*
X1056465Y-180605D01*
X1055592Y-178856D01*
X1054281Y-177397D01*
X1052535Y-176814D01*
G01X1069598Y-194314D02*
X1070035Y-190523D01*
X1070690Y-187314D01*
X1071563Y-184397D01*
X1072655Y-181189D01*
X1074402Y-176814D01*
X1065668D01*
G01X1083605Y-194897D02*
X1091465Y-176814D01*
G01X1100887Y-179731D02*
X1102197Y-177981D01*
X1103725Y-177106D01*
X1105472Y-176814D01*
X1107655Y-177397D01*
X1109183Y-178856D01*
X1109620Y-180605D01*
X1109402Y-182356D01*
X1108528Y-183814D01*
X1104162Y-186731D01*
X1102197Y-188772D01*
X1100887Y-191690D01*
X1100450Y-194314D01*
X1109620D01*
G01X1122535Y-176814D02*
X1120788Y-177397D01*
X1119478Y-178856D01*
X1118605Y-180605D01*
X1117950Y-182939D01*
X1117732Y-185564D01*
X1117950Y-188189D01*
X1118605Y-190523D01*
X1119478Y-192273D01*
X1120788Y-193731D01*
X1122535Y-194314D01*
X1124281Y-193731D01*
X1125592Y-192273D01*
X1126465Y-190523D01*
X1127120Y-188189D01*
X1127338Y-185564D01*
X1127120Y-182939D01*
X1126465Y-180605D01*
X1125592Y-178856D01*
X1124281Y-177397D01*
X1122535Y-176814D01*
G01X1140035Y-194314D02*
Y-176814D01*
X1137415Y-180314D01*
G01Y-194314D02*
X1142655D01*
G01X1157098D02*
X1157535Y-190523D01*
X1158190Y-187314D01*
X1159063Y-184397D01*
X1160155Y-181189D01*
X1161902Y-176814D01*
X1153168D01*
G01X1047732Y-149314D02*
Y-131814D01*
X1052098D01*
X1053845Y-132689D01*
X1055155Y-133856D01*
X1056247Y-135605D01*
X1057120Y-137648D01*
X1057338Y-140564D01*
X1057120Y-143481D01*
X1056247Y-145523D01*
X1055155Y-147273D01*
X1053845Y-148439D01*
X1052098Y-149314D01*
X1047732D01*
G01X1073965D02*
Y-137648D01*
G01Y-139689D02*
X1073092Y-138523D01*
X1071781Y-137939D01*
X1070253Y-137648D01*
X1068725Y-138231D01*
X1067415Y-139397D01*
X1066541Y-141147D01*
X1066105Y-143481D01*
X1066541Y-145814D01*
X1067415Y-147564D01*
X1068725Y-148731D01*
X1070253Y-149314D01*
X1071781Y-149022D01*
X1073092Y-148148D01*
X1073965Y-146981D01*
G01X1087535Y-131814D02*
Y-149314D01*
G01X1084478Y-137648D02*
X1090592D01*
G01X1101760Y-141439D02*
X1108747D01*
X1108092Y-139397D01*
X1107000Y-138231D01*
X1105472Y-137648D01*
X1103943Y-137939D01*
X1102633Y-138814D01*
X1101760Y-140856D01*
X1101323Y-142606D01*
Y-144356D01*
X1101760Y-146106D01*
X1102852Y-147856D01*
X1104162Y-149022D01*
X1105690Y-149314D01*
X1107218Y-148731D01*
X1108747Y-146981D01*
G01X36307Y1887D02*
Y9687D01*
X48907D01*
Y1887D01*
X36307D01*
G01X39807Y8287D02*
X39207Y8187D01*
X38707Y7687D01*
X38307Y7187D01*
X38107Y6587D01*
X38007Y5787D01*
X38107Y5087D01*
X38307Y4387D01*
X38707Y3887D01*
X39207Y3487D01*
X39807Y3287D01*
X40507Y3487D01*
X41007Y3887D01*
X41307Y4387D01*
X41607Y5087D01*
X41707Y5787D01*
X41607Y6587D01*
X41307Y7187D01*
X41007Y7687D01*
X40507Y8187D01*
X39807Y8287D01*
G01X36307Y136533D02*
Y144333D01*
X48907D01*
Y136533D01*
X36307D01*
G01X39807Y142933D02*
X39207Y142833D01*
X38707Y142333D01*
X38307Y141833D01*
X38107Y141233D01*
X38007Y140433D01*
X38107Y139733D01*
X38307Y139033D01*
X38707Y138533D01*
X39207Y138133D01*
X39807Y137933D01*
X40507Y138133D01*
X41007Y138533D01*
X41307Y139033D01*
X41607Y139733D01*
X41707Y140433D01*
X41607Y141233D01*
X41307Y141833D01*
X41007Y142333D01*
X40507Y142833D01*
X39807Y142933D01*
G01X36307Y271180D02*
Y278980D01*
X48907D01*
Y271180D01*
X36307D01*
G01X39807Y277580D02*
X39207Y277480D01*
X38707Y276980D01*
X38307Y276480D01*
X38107Y275880D01*
X38007Y275080D01*
X38107Y274380D01*
X38307Y273680D01*
X38707Y273180D01*
X39207Y272780D01*
X39807Y272580D01*
X40507Y272780D01*
X41007Y273180D01*
X41307Y273680D01*
X41607Y274380D01*
X41707Y275080D01*
X41607Y275880D01*
X41307Y276480D01*
X41007Y276980D01*
X40507Y277480D01*
X39807Y277580D01*
G01X36307Y405826D02*
Y413626D01*
X48907D01*
Y405826D01*
X36307D01*
G01X39807Y412226D02*
X39207Y412126D01*
X38707Y411626D01*
X38307Y411126D01*
X38107Y410526D01*
X38007Y409726D01*
X38107Y409026D01*
X38307Y408326D01*
X38707Y407826D01*
X39207Y407426D01*
X39807Y407226D01*
X40507Y407426D01*
X41007Y407826D01*
X41307Y408326D01*
X41607Y409026D01*
X41707Y409726D01*
X41607Y410526D01*
X41307Y411126D01*
X41007Y411626D01*
X40507Y412126D01*
X39807Y412226D01*
G01X36307Y540472D02*
Y548272D01*
X48907D01*
Y540472D01*
X36307D01*
G01X39807Y546872D02*
X39207Y546772D01*
X38707Y546272D01*
X38307Y545772D01*
X38107Y545172D01*
X38007Y544372D01*
X38107Y543672D01*
X38307Y542972D01*
X38707Y542472D01*
X39207Y542072D01*
X39807Y541872D01*
X40507Y542072D01*
X41007Y542472D01*
X41307Y542972D01*
X41607Y543672D01*
X41707Y544372D01*
X41607Y545172D01*
X41307Y545772D01*
X41007Y546272D01*
X40507Y546772D01*
X39807Y546872D01*
G01X36307Y675118D02*
Y682918D01*
X48907D01*
Y675118D01*
X36307D01*
G01X39807Y676518D02*
Y681518D01*
X38807Y680518D01*
G01Y676518D02*
X40807D01*
G01X36307Y809764D02*
Y817564D01*
X48907D01*
Y809764D01*
X36307D01*
G01X39807Y811164D02*
Y816164D01*
X38807Y815164D01*
G01Y811164D02*
X40807D01*
G01X45407Y3287D02*
Y8287D01*
X44407Y7287D01*
G01Y3287D02*
X46407D01*
G01X48417Y42800D02*
Y40300D01*
X50083D01*
G01X53183D02*
X51517D01*
Y42800D01*
X53183D01*
G01X52517Y41592D02*
X51517D01*
G01X54533Y40300D02*
Y42800D01*
X55367D01*
X55700Y42675D01*
X55950Y42508D01*
X56158Y42258D01*
X56325Y41967D01*
X56367Y41550D01*
X56325Y41133D01*
X56158Y40842D01*
X55950Y40592D01*
X55700Y40425D01*
X55367Y40300D01*
X54533D01*
G01X58550D02*
Y42800D01*
X58050Y42300D01*
G01Y40300D02*
X59050D01*
G01X49143Y53455D02*
Y64655D01*
X57943D01*
Y53455D01*
X49143D01*
G01X43607Y138933D02*
X44107Y138333D01*
X44807Y138033D01*
X45507Y137933D01*
X46207Y138033D01*
X46807Y138433D01*
X47307Y138933D01*
Y139433D01*
X47207Y140033D01*
X46607Y140433D01*
X46007Y140633D01*
X45307D01*
G01X46007D02*
X46507Y140833D01*
X46907Y141333D01*
X47107Y141833D01*
X46907Y142333D01*
X46507Y142733D01*
X45807Y142933D01*
X45007Y142833D01*
X44307Y142533D01*
G01X43607Y273380D02*
X44107Y272980D01*
X44707Y272680D01*
X45407Y272580D01*
X46207Y272780D01*
X46807Y273080D01*
X47207Y273680D01*
X47307Y274380D01*
X47107Y274980D01*
X46707Y275480D01*
X46107Y275780D01*
X45507Y275880D01*
X44907Y275780D01*
X44207Y275480D01*
X44407Y277580D01*
X46707D01*
G01X45307Y407226D02*
X45407Y408326D01*
X46007Y410126D01*
X46407Y411026D01*
X47107Y412226D01*
X43807D01*
G01X44007Y542472D02*
X44607Y542072D01*
X45307Y541872D01*
X45907Y542072D01*
X46507Y542572D01*
X46907Y543272D01*
X47107Y544072D01*
Y544972D01*
X46907Y545772D01*
X46507Y546372D01*
X46007Y546772D01*
X45407Y546872D01*
X44807Y546772D01*
X44307Y546372D01*
X43907Y545872D01*
X43807Y545272D01*
X43907Y544672D01*
X44307Y544072D01*
X44807Y543772D01*
X45407Y543672D01*
X46107Y543772D01*
X46607Y544272D01*
X47107Y544972D01*
G01X45407Y676518D02*
Y681518D01*
X44407Y680518D01*
G01Y676518D02*
X46407D01*
G01X43607Y812164D02*
X44107Y811564D01*
X44807Y811264D01*
X45507Y811164D01*
X46207Y811264D01*
X46807Y811664D01*
X47307Y812164D01*
Y812664D01*
X47207Y813264D01*
X46607Y813664D01*
X46007Y813864D01*
X45307D01*
G01X46007D02*
X46507Y814064D01*
X46907Y814564D01*
X47107Y815064D01*
X46907Y815564D01*
X46507Y815964D01*
X45807Y816164D01*
X45007Y816064D01*
X44307Y815764D01*
G01X183152Y49577D02*
Y47077D01*
X184818D01*
G01X187918D02*
X186252D01*
Y49577D01*
X187918D01*
G01X187252Y48369D02*
X186252D01*
G01X189268Y47077D02*
Y49577D01*
X190102D01*
X190435Y49452D01*
X190685Y49285D01*
X190893Y49035D01*
X191060Y48744D01*
X191102Y48327D01*
X191060Y47910D01*
X190893Y47619D01*
X190685Y47369D01*
X190435Y47202D01*
X190102Y47077D01*
X189268D01*
G01X192493Y49160D02*
X192743Y49410D01*
X193035Y49535D01*
X193368Y49577D01*
X193785Y49494D01*
X194077Y49285D01*
X194160Y49035D01*
X194118Y48785D01*
X193952Y48577D01*
X193118Y48160D01*
X192743Y47869D01*
X192493Y47452D01*
X192410Y47077D01*
X194160D01*
G01X173356Y53455D02*
Y64655D01*
X182156D01*
Y53455D01*
X173356D01*
G01X323700Y20700D02*
Y25700D01*
X322700Y24700D01*
G01Y20700D02*
X324700D01*
G01X327717Y22783D02*
X328300Y23367D01*
X328800Y23700D01*
X329467Y23867D01*
X330050Y23700D01*
X330467Y23367D01*
X330800Y22867D01*
X330883Y22283D01*
X330800Y21783D01*
X330467Y21283D01*
X329967Y20867D01*
X329383Y20700D01*
X328717Y20867D01*
X328133Y21367D01*
X327800Y22117D01*
X327717Y22950D01*
X327883Y24033D01*
X328133Y24617D01*
X328550Y25200D01*
X329133Y25617D01*
X329717Y25700D01*
X330300Y25533D01*
X330717Y25117D01*
G01X333067Y21700D02*
X333567Y21117D01*
X334233Y20783D01*
X334983Y20700D01*
X335650Y20783D01*
X336317Y21200D01*
X336733Y21700D01*
X336817Y22200D01*
X336650Y22783D01*
X336067Y23200D01*
X335483Y23367D01*
X334733D01*
G01X335483D02*
X335983Y23617D01*
X336400Y24033D01*
X336567Y24533D01*
X336400Y25033D01*
X335983Y25450D01*
X335233Y25700D01*
X334483Y25617D01*
X333733Y25283D01*
G01X341500Y20700D02*
Y25700D01*
X338417Y22117D01*
X342583D01*
G01X345933Y20700D02*
X346100Y21783D01*
X346350Y22700D01*
X346683Y23533D01*
X347100Y24450D01*
X347767Y25700D01*
X344433D01*
G01X350617Y22367D02*
X352783D01*
G01X357300Y20700D02*
Y25700D01*
X356300Y24700D01*
G01Y20700D02*
X358300D01*
G01X324667Y16317D02*
X325000Y16567D01*
X325250Y16983D01*
X325417Y17567D01*
X325250Y18067D01*
X324917Y18400D01*
X324333Y18650D01*
X322083D01*
Y13650D01*
X324833D01*
X325417Y13983D01*
X325750Y14483D01*
X325917Y15067D01*
X325750Y15650D01*
X325250Y16150D01*
X324667Y16317D01*
X322083D01*
G01X330600Y13650D02*
Y18650D01*
X327517Y15067D01*
X331683D01*
G01X335200Y13650D02*
X335783Y13733D01*
X336450Y13983D01*
X336867Y14400D01*
X337033Y14983D01*
X336867Y15567D01*
X336367Y16067D01*
X335617Y16317D01*
X334783D01*
X334283Y16483D01*
X333867Y16900D01*
X333700Y17483D01*
X333950Y18067D01*
X334533Y18483D01*
X335200Y18650D01*
X335867Y18483D01*
X336450Y18067D01*
X336700Y17483D01*
X336533Y16900D01*
X336117Y16483D01*
X335617Y16317D01*
X334783D01*
X334033Y16067D01*
X333533Y15567D01*
X333367Y14983D01*
X333533Y14400D01*
X333950Y13983D01*
X334617Y13733D01*
X335200Y13650D01*
G01X340800Y13483D02*
X340633Y13567D01*
Y13733D01*
X340800Y13817D01*
X340967Y13733D01*
Y13567D01*
X340800Y13483D01*
G01X346400Y18650D02*
X345733Y18483D01*
X345233Y18067D01*
X344900Y17567D01*
X344650Y16900D01*
X344567Y16150D01*
X344650Y15400D01*
X344900Y14733D01*
X345233Y14233D01*
X345733Y13817D01*
X346400Y13650D01*
X347067Y13817D01*
X347567Y14233D01*
X347900Y14733D01*
X348150Y15400D01*
X348233Y16150D01*
X348150Y16900D01*
X347900Y17567D01*
X347567Y18067D01*
X347067Y18483D01*
X346400Y18650D01*
G01X352000Y13650D02*
Y18650D01*
X351000Y17650D01*
G01Y13650D02*
X353000D01*
G01X357600D02*
Y18650D01*
X356600Y17650D01*
G01Y13650D02*
X358600D01*
G01X363200D02*
Y18650D01*
X362200Y17650D01*
G01Y13650D02*
X364200D01*
G01X367383Y14233D02*
X367967Y13817D01*
X368633Y13650D01*
X369300Y13817D01*
X369883Y14317D01*
X370300Y15067D01*
X370467Y15817D01*
Y16733D01*
X370300Y17483D01*
X369883Y18150D01*
X369383Y18483D01*
X368800Y18650D01*
X368133Y18483D01*
X367633Y18150D01*
X367300Y17650D01*
X367133Y16983D01*
X367300Y16400D01*
X367717Y15817D01*
X368217Y15483D01*
X368800Y15400D01*
X369467Y15567D01*
X369967Y15983D01*
X370467Y16733D01*
G01X374400Y13483D02*
X374233Y13567D01*
Y13733D01*
X374400Y13817D01*
X374567Y13733D01*
Y13567D01*
X374400Y13483D01*
G01X380000Y18650D02*
X379333Y18483D01*
X378833Y18067D01*
X378500Y17567D01*
X378250Y16900D01*
X378167Y16150D01*
X378250Y15400D01*
X378500Y14733D01*
X378833Y14233D01*
X379333Y13817D01*
X380000Y13650D01*
X380667Y13817D01*
X381167Y14233D01*
X381500Y14733D01*
X381750Y15400D01*
X381833Y16150D01*
X381750Y16900D01*
X381500Y17567D01*
X381167Y18067D01*
X380667Y18483D01*
X380000Y18650D01*
G01X385600D02*
X384933Y18483D01*
X384433Y18067D01*
X384100Y17567D01*
X383850Y16900D01*
X383767Y16150D01*
X383850Y15400D01*
X384100Y14733D01*
X384433Y14233D01*
X384933Y13817D01*
X385600Y13650D01*
X386267Y13817D01*
X386767Y14233D01*
X387100Y14733D01*
X387350Y15400D01*
X387433Y16150D01*
X387350Y16900D01*
X387100Y17567D01*
X386767Y18067D01*
X386267Y18483D01*
X385600Y18650D01*
G01X391200Y13650D02*
Y18650D01*
X390200Y17650D01*
G01Y13650D02*
X392200D01*
G01X396800D02*
Y18650D01*
X395800Y17650D01*
G01Y13650D02*
X397800D01*
G01X322333Y6650D02*
Y11650D01*
X324500Y7483D01*
X326667Y11650D01*
Y6650D01*
G01X328017D02*
X330100Y11650D01*
X332183Y6650D01*
G01X331433Y8400D02*
X328767D01*
G01X333867Y6650D02*
Y11650D01*
X335533D01*
X336200Y11400D01*
X336700Y11067D01*
X337117Y10567D01*
X337450Y9983D01*
X337533Y9150D01*
X337450Y8317D01*
X337117Y7733D01*
X336700Y7233D01*
X336200Y6900D01*
X335533Y6650D01*
X333867D01*
G01X342967D02*
X339633D01*
Y11650D01*
X342967D01*
G01X341633Y9233D02*
X339633D01*
G01X351500Y11650D02*
X353500D01*
G01X352500D02*
Y6650D01*
G01X351500D02*
X353500D01*
G01X356183D02*
Y11650D01*
X360017Y6650D01*
Y11650D01*
G01X369300D02*
Y6650D01*
G01X367383Y11650D02*
X371217D01*
G01X372817Y6650D02*
X374900Y11650D01*
X376983Y6650D01*
G01X376233Y8400D02*
X373567D01*
G01X379500Y11650D02*
X381500D01*
G01X380500D02*
Y6650D01*
G01X379500D02*
X381500D01*
G01X383600Y11650D02*
X384767Y6650D01*
X386100Y11650D01*
X387433Y6650D01*
X388600Y11650D01*
G01X389617Y6650D02*
X391700Y11650D01*
X393783Y6650D01*
G01X393033Y8400D02*
X390367D01*
G01X395383Y6650D02*
Y11650D01*
X399217Y6650D01*
Y11650D01*
G01X325167Y30817D02*
X325500Y31067D01*
X325750Y31483D01*
X325917Y32067D01*
X325750Y32567D01*
X325417Y32900D01*
X324833Y33150D01*
X322583D01*
Y28150D01*
X325333D01*
X325917Y28483D01*
X326250Y28983D01*
X326417Y29567D01*
X326250Y30150D01*
X325750Y30650D01*
X325167Y30817D01*
X322583D01*
G01X328933Y28150D02*
Y31483D01*
G01Y30817D02*
X329350Y31150D01*
X329767Y31400D01*
X330350Y31483D01*
X330767Y31400D01*
X331267Y31150D01*
G01X333950Y26650D02*
X334450Y26483D01*
X335117Y26650D01*
X335533Y26983D01*
X335867Y27400D01*
X336367Y28733D01*
X337450Y31483D01*
G01X334783D02*
X336367Y28733D01*
G01X342633Y31067D02*
X342050Y31400D01*
X341550Y31483D01*
X340883Y31317D01*
X340383Y30983D01*
X340050Y30400D01*
X339967Y29817D01*
X340050Y29233D01*
X340383Y28733D01*
X340883Y28317D01*
X341550Y28150D01*
X342133Y28317D01*
X342633Y28650D01*
G01X345650Y30400D02*
X348317D01*
X348067Y30983D01*
X347650Y31317D01*
X347067Y31483D01*
X346483Y31400D01*
X345983Y31150D01*
X345650Y30567D01*
X345483Y30067D01*
Y29567D01*
X345650Y29067D01*
X346067Y28567D01*
X346567Y28233D01*
X347150Y28150D01*
X347733Y28317D01*
X348317Y28817D01*
G01X359933Y32733D02*
X359433Y32983D01*
X358850Y33150D01*
X358183D01*
X357433Y32900D01*
X356850Y32483D01*
X356433Y31983D01*
X356100Y31150D01*
X356017Y30400D01*
X356183Y29650D01*
X356433Y29150D01*
X356933Y28650D01*
X357517Y28317D01*
X358100Y28150D01*
X358683D01*
X359267Y28317D01*
X359767Y28567D01*
X360183Y28900D01*
G01X365200Y28150D02*
Y31483D01*
G01Y30900D02*
X364867Y31233D01*
X364367Y31400D01*
X363783Y31483D01*
X363200Y31317D01*
X362700Y30983D01*
X362367Y30483D01*
X362200Y29817D01*
X362367Y29150D01*
X362700Y28650D01*
X363200Y28317D01*
X363783Y28150D01*
X364367Y28233D01*
X364867Y28483D01*
X365200Y28817D01*
G01X367883Y28150D02*
Y31483D01*
G01Y30650D02*
X368217Y31067D01*
X368717Y31400D01*
X369383Y31483D01*
X369967Y31400D01*
X370467Y31067D01*
X370717Y30483D01*
Y28150D01*
G01X373150Y26650D02*
X373650Y26483D01*
X374317Y26650D01*
X374733Y26983D01*
X375067Y27400D01*
X375567Y28733D01*
X376650Y31483D01*
G01X373983D02*
X375567Y28733D01*
G01X380500Y28150D02*
X380000Y28233D01*
X379500Y28567D01*
X379167Y29150D01*
X379000Y29817D01*
X379167Y30483D01*
X379500Y31067D01*
X380000Y31400D01*
X380500Y31483D01*
X381000Y31400D01*
X381500Y31067D01*
X381833Y30483D01*
X381917Y29817D01*
X381833Y29150D01*
X381500Y28567D01*
X381000Y28233D01*
X380500Y28150D01*
G01X384683D02*
Y31483D01*
G01Y30650D02*
X385017Y31067D01*
X385517Y31400D01*
X386183Y31483D01*
X386767Y31400D01*
X387267Y31067D01*
X387517Y30483D01*
Y28150D01*
G01X395633Y33150D02*
Y28150D01*
X398967D01*
G01X404567D02*
X401233D01*
Y33150D01*
X404567D01*
G01X403233Y30733D02*
X401233D01*
G01X406667Y28150D02*
Y33150D01*
X408333D01*
X409000Y32900D01*
X409500Y32567D01*
X409917Y32067D01*
X410250Y31483D01*
X410333Y30650D01*
X410250Y29817D01*
X409917Y29233D01*
X409500Y28733D01*
X409000Y28400D01*
X408333Y28150D01*
X406667D01*
G01X420367Y30817D02*
X420700Y31067D01*
X420950Y31483D01*
X421117Y32067D01*
X420950Y32567D01*
X420617Y32900D01*
X420033Y33150D01*
X417783D01*
Y28150D01*
X420533D01*
X421117Y28483D01*
X421450Y28983D01*
X421617Y29567D01*
X421450Y30150D01*
X420950Y30650D01*
X420367Y30817D01*
X417783D01*
G01X425300Y28150D02*
X424800Y28233D01*
X424300Y28567D01*
X423967Y29150D01*
X423800Y29817D01*
X423967Y30483D01*
X424300Y31067D01*
X424800Y31400D01*
X425300Y31483D01*
X425800Y31400D01*
X426300Y31067D01*
X426633Y30483D01*
X426717Y29817D01*
X426633Y29150D01*
X426300Y28567D01*
X425800Y28233D01*
X425300Y28150D01*
G01X432400D02*
Y31483D01*
G01Y30900D02*
X432067Y31233D01*
X431567Y31400D01*
X430983Y31483D01*
X430400Y31317D01*
X429900Y30983D01*
X429567Y30483D01*
X429400Y29817D01*
X429567Y29150D01*
X429900Y28650D01*
X430400Y28317D01*
X430983Y28150D01*
X431567Y28233D01*
X432067Y28483D01*
X432400Y28817D01*
G01X435333Y28150D02*
Y31483D01*
G01Y30817D02*
X435750Y31150D01*
X436167Y31400D01*
X436750Y31483D01*
X437167Y31400D01*
X437667Y31150D01*
G01X443600Y33150D02*
Y28150D01*
G01Y28900D02*
X443267Y28483D01*
X442767Y28233D01*
X442183Y28150D01*
X441517Y28317D01*
X441017Y28733D01*
X440683Y29233D01*
X440600Y29817D01*
X440683Y30400D01*
X441017Y30900D01*
X441517Y31317D01*
X442183Y31483D01*
X442767Y31400D01*
X443183Y31233D01*
X443600Y30900D01*
G01X298817Y45000D02*
Y42500D01*
X300483D01*
G01X303583D02*
X301917D01*
Y45000D01*
X303583D01*
G01X302917Y43792D02*
X301917D01*
G01X304933Y42500D02*
Y45000D01*
X305767D01*
X306100Y44875D01*
X306350Y44708D01*
X306558Y44458D01*
X306725Y44167D01*
X306767Y43750D01*
X306725Y43333D01*
X306558Y43042D01*
X306350Y42792D01*
X306100Y42625D01*
X305767Y42500D01*
X304933D01*
G01X308033Y43000D02*
X308283Y42708D01*
X308617Y42542D01*
X308992Y42500D01*
X309325Y42542D01*
X309658Y42750D01*
X309867Y43000D01*
X309908Y43250D01*
X309825Y43542D01*
X309533Y43750D01*
X309242Y43833D01*
X308867D01*
G01X309242D02*
X309492Y43958D01*
X309700Y44167D01*
X309783Y44417D01*
X309700Y44667D01*
X309492Y44875D01*
X309117Y45000D01*
X308742Y44958D01*
X308367Y44792D01*
G01X297569Y53455D02*
Y64655D01*
X306369D01*
Y53455D01*
X297569D01*
G01X421781D02*
Y64655D01*
X430581D01*
Y53455D01*
X421781D01*
G01X426360Y48915D02*
Y46415D01*
X428026D01*
G01X431126D02*
X429460D01*
Y48915D01*
X431126D01*
G01X430460Y47707D02*
X429460D01*
G01X432476Y46415D02*
Y48915D01*
X433310D01*
X433643Y48790D01*
X433893Y48623D01*
X434101Y48373D01*
X434268Y48082D01*
X434310Y47665D01*
X434268Y47248D01*
X434101Y46957D01*
X433893Y46707D01*
X433643Y46540D01*
X433310Y46415D01*
X432476D01*
G01X436993D02*
Y48915D01*
X435451Y47123D01*
X437535D01*
G01X546217Y43800D02*
Y41300D01*
X547883D01*
G01X550983D02*
X549317D01*
Y43800D01*
X550983D01*
G01X550317Y42592D02*
X549317D01*
G01X552333Y41300D02*
Y43800D01*
X553167D01*
X553500Y43675D01*
X553750Y43508D01*
X553958Y43258D01*
X554125Y42967D01*
X554167Y42550D01*
X554125Y42133D01*
X553958Y41842D01*
X553750Y41592D01*
X553500Y41425D01*
X553167Y41300D01*
X552333D01*
G01X555433Y41675D02*
X555683Y41467D01*
X555975Y41342D01*
X556350Y41300D01*
X556725Y41383D01*
X557017Y41550D01*
X557225Y41842D01*
X557267Y42175D01*
X557183Y42508D01*
X556975Y42717D01*
X556683Y42883D01*
X556392Y42925D01*
X556100Y42883D01*
X555725Y42717D01*
X555850Y43800D01*
X556975D01*
G01X545994Y53455D02*
Y64655D01*
X554794D01*
Y53455D01*
X545994D01*
G01X583600Y33900D02*
Y6100D01*
X611400D01*
Y33900D01*
X583600D01*
G01X674136Y49444D02*
Y46944D01*
X675802D01*
G01X678902D02*
X677236D01*
Y49444D01*
X678902D01*
G01X678236Y48236D02*
X677236D01*
G01X680252Y46944D02*
Y49444D01*
X681086D01*
X681419Y49319D01*
X681669Y49152D01*
X681877Y48902D01*
X682044Y48611D01*
X682086Y48194D01*
X682044Y47777D01*
X681877Y47486D01*
X681669Y47236D01*
X681419Y47069D01*
X681086Y46944D01*
X680252D01*
G01X683477Y47986D02*
X683769Y48277D01*
X684019Y48444D01*
X684352Y48527D01*
X684644Y48444D01*
X684852Y48277D01*
X685019Y48027D01*
X685061Y47736D01*
X685019Y47486D01*
X684852Y47236D01*
X684602Y47027D01*
X684311Y46944D01*
X683977Y47027D01*
X683686Y47277D01*
X683519Y47652D01*
X683477Y48069D01*
X683561Y48611D01*
X683686Y48902D01*
X683894Y49194D01*
X684186Y49402D01*
X684477Y49444D01*
X684769Y49361D01*
X684977Y49152D01*
G01X670206Y53455D02*
Y64655D01*
X679006D01*
Y53455D01*
X670206D01*
G01X764678Y117011D02*
Y109211D01*
X752078D01*
Y117011D01*
X764678D01*
G01X757178Y111411D02*
X756678Y110911D01*
X756078Y110711D01*
X755378Y110611D01*
X754578Y110711D01*
X753978Y111211D01*
X753778Y111711D01*
X753878Y112211D01*
X754178Y112611D01*
X755878Y113411D01*
X756678Y114011D01*
X757178Y114811D01*
X757278Y115611D01*
X753778D01*
G01X764678Y251657D02*
Y243857D01*
X752078D01*
Y251657D01*
X764678D01*
G01X754578Y250257D02*
Y245257D01*
X757678Y248857D01*
X753478D01*
G01X764678Y386303D02*
Y378503D01*
X752078D01*
Y386303D01*
X764678D01*
G01X757178Y382803D02*
X756578Y382203D01*
X756078Y381903D01*
X755378Y381703D01*
X754778Y381903D01*
X754378Y382203D01*
X754078Y382703D01*
X753978Y383303D01*
X754078Y383803D01*
X754378Y384303D01*
X754878Y384703D01*
X755478Y384903D01*
X756178Y384703D01*
X756678Y384203D01*
X757078Y383503D01*
X757178Y382603D01*
X756978Y381503D01*
X756678Y381003D01*
X756278Y380403D01*
X755678Y380003D01*
X755178Y379903D01*
X754578Y380003D01*
X754178Y380503D01*
G01X764678Y520949D02*
Y513149D01*
X752078D01*
Y520949D01*
X764678D01*
G01X755578Y519549D02*
X754978Y519449D01*
X754278Y519149D01*
X753878Y518749D01*
X753678Y518149D01*
X753878Y517649D01*
X754378Y517149D01*
X755178Y516849D01*
X755978D01*
X756478Y516649D01*
X756878Y516249D01*
X757078Y515649D01*
X756778Y515149D01*
X756178Y514649D01*
X755578Y514549D01*
X754878Y514649D01*
X754278Y515149D01*
X754078Y515649D01*
X754178Y516249D01*
X754678Y516649D01*
X755178Y516849D01*
X755978D01*
X756678Y517149D01*
X757178Y517649D01*
X757378Y518149D01*
X757178Y518749D01*
X756778Y519149D01*
X756178Y519449D01*
X755578Y519549D01*
G01X764678Y655595D02*
Y647795D01*
X752078D01*
Y655595D01*
X764678D01*
G01X755578Y649195D02*
X756178Y649295D01*
X756678Y649795D01*
X757078Y650295D01*
X757278Y650895D01*
X757378Y651695D01*
X757278Y652395D01*
X757078Y653095D01*
X756678Y653595D01*
X756178Y653995D01*
X755578Y654195D01*
X754878Y653995D01*
X754378Y653595D01*
X754078Y653095D01*
X753778Y652395D01*
X753678Y651695D01*
X753778Y650895D01*
X754078Y650295D01*
X754378Y649795D01*
X754878Y649295D01*
X755578Y649195D01*
G01X764678Y790241D02*
Y782441D01*
X752078D01*
Y790241D01*
X764678D01*
G01X757178Y784641D02*
X756678Y784141D01*
X756078Y783941D01*
X755378Y783841D01*
X754578Y783941D01*
X753978Y784441D01*
X753778Y784941D01*
X753878Y785441D01*
X754178Y785841D01*
X755878Y786641D01*
X756678Y787241D01*
X757178Y788041D01*
X757278Y788841D01*
X753778D01*
G01X764678Y924887D02*
Y917087D01*
X752078D01*
Y924887D01*
X764678D01*
G01X754578Y923487D02*
Y918487D01*
X757678Y922087D01*
X753478D01*
G01X761178Y110611D02*
X761778Y110711D01*
X762278Y111211D01*
X762678Y111711D01*
X762878Y112311D01*
X762978Y113111D01*
X762878Y113811D01*
X762678Y114511D01*
X762278Y115011D01*
X761778Y115411D01*
X761178Y115611D01*
X760478Y115411D01*
X759978Y115011D01*
X759678Y114511D01*
X759378Y113811D01*
X759278Y113111D01*
X759378Y112311D01*
X759678Y111711D01*
X759978Y111211D01*
X760478Y110711D01*
X761178Y110611D01*
G01Y245257D02*
X761778Y245357D01*
X762278Y245857D01*
X762678Y246357D01*
X762878Y246957D01*
X762978Y247757D01*
X762878Y248457D01*
X762678Y249157D01*
X762278Y249657D01*
X761778Y250057D01*
X761178Y250257D01*
X760478Y250057D01*
X759978Y249657D01*
X759678Y249157D01*
X759378Y248457D01*
X759278Y247757D01*
X759378Y246957D01*
X759678Y246357D01*
X759978Y245857D01*
X760478Y245357D01*
X761178Y245257D01*
G01Y379903D02*
X761778Y380003D01*
X762278Y380503D01*
X762678Y381003D01*
X762878Y381603D01*
X762978Y382403D01*
X762878Y383103D01*
X762678Y383803D01*
X762278Y384303D01*
X761778Y384703D01*
X761178Y384903D01*
X760478Y384703D01*
X759978Y384303D01*
X759678Y383803D01*
X759378Y383103D01*
X759278Y382403D01*
X759378Y381603D01*
X759678Y381003D01*
X759978Y380503D01*
X760478Y380003D01*
X761178Y379903D01*
G01Y514549D02*
X761778Y514649D01*
X762278Y515149D01*
X762678Y515649D01*
X762878Y516249D01*
X762978Y517049D01*
X762878Y517749D01*
X762678Y518449D01*
X762278Y518949D01*
X761778Y519349D01*
X761178Y519549D01*
X760478Y519349D01*
X759978Y518949D01*
X759678Y518449D01*
X759378Y517749D01*
X759278Y517049D01*
X759378Y516249D01*
X759678Y515649D01*
X759978Y515149D01*
X760478Y514649D01*
X761178Y514549D01*
G01Y654195D02*
Y649195D01*
X762178Y650195D01*
G01Y654195D02*
X760178D01*
G01X761178Y788841D02*
Y783841D01*
X762178Y784841D01*
G01Y788841D02*
X760178D01*
G01X761178Y923487D02*
Y918487D01*
X762178Y919487D01*
G01Y923487D02*
X760178D01*
M02*
